FILE_TYPE = MACRO_DRAWING;
SET COLOR_WIRE YELLOW;
SET COLOR_PROP MONO;
SET COLOR_DOT WHITE;
SET COLOR_ARC YELLOW;
SET COLOR_BODY GREEN;
SET COLOR_NOTE MONO;
SET PROP_DISPLAY VALUE;
SET PAGE_NUMBER P229;
FORCEADD GND..1
(-475 -775);
FORCEPROP 3 LASTPIN (-475 -725) SIG_NAME GND\g
J 0
(-465 -715);
DISPLAY 0.659574 (-465 -715);
PAINT MONO (-465 -715);
DISPLAY INVISIBLE (-465 -715);
FORCEPROP 1 LAST HDL_POWER GND
J 0
(-475 -625);
DISPLAY 0.893617 (-475 -625);
PAINT GREEN (-475 -625);
DISPLAY INVISIBLE (-475 -625);
FORCEPROP 1 LAST BODY_TYPE PLUMBING
J 0
(-520 -818);
DISPLAY 0.340426 (-520 -818);
PAINT GREEN (-520 -818);
DISPLAY INVISIBLE (-520 -818);
FORCEPROP 1 LAST SIZE 1B
J 0
(-400 -825);
DISPLAY 0.893617 (-400 -825);
PAINT GREEN (-400 -825);
DISPLAY INVISIBLE (-400 -825);
FORCEPROP 2 LAST CDS_LIB mstr_symbols
J 0
(-475 -775);
PAINT MONO (-475 -775);
DISPLAY INVISIBLE (-475 -775);
FORCEPROP 1 LAST VOLTAGE 0.0V
J 0
(-520 -818);
DISPLAY 0.340426 (-520 -818);
PAINT SKYBLUE (-520 -818);
DISPLAY INVISIBLE (-520 -818);
FORCEPROP 1 LAST PATH I1
J 0
(-400 -775);
DISPLAY 0.872340 (-400 -775);
PAINT AQUA (-400 -775);
DISPLAY INVISIBLE (-400 -775);
FORCEADD GND..1
(-75 1950);
FORCEPROP 3 LASTPIN (-75 2000) SIG_NAME GND\g
J 0
(-65 2010);
DISPLAY 0.659574 (-65 2010);
PAINT MONO (-65 2010);
DISPLAY INVISIBLE (-65 2010);
FORCEPROP 2 LAST ROOM VTT_GHJ_PWR_VR
J 0
(-580 2030);
DISPLAY 1.021277 (-580 2030);
PAINT ORANGE (-580 2030);
DISPLAY INVISIBLE (-580 2030);
FORCEPROP 1 LAST BODY_TYPE PLUMBING
J 0
(-120 1907);
DISPLAY 0.340426 (-120 1907);
PAINT GREEN (-120 1907);
DISPLAY INVISIBLE (-120 1907);
FORCEPROP 2 LAST BOM_COST MEM_VRD_VTT_GHJ
J 0
(-580 2080);
DISPLAY 1.021277 (-580 2080);
PAINT ORANGE (-580 2080);
DISPLAY INVISIBLE (-580 2080);
FORCEPROP 1 LAST VOLTAGE 0.0V
J 0
(-120 1907);
DISPLAY 0.340426 (-120 1907);
PAINT SKYBLUE (-120 1907);
DISPLAY INVISIBLE (-120 1907);
FORCEPROP 2 LAST CDS_LIB mstr_symbols
J 0
(-75 1950);
DISPLAY 0.744681 (-75 1950);
PAINT MONO (-75 1950);
DISPLAY INVISIBLE (-75 1950);
FORCEPROP 1 LAST HDL_POWER GND
J 0
(-75 2100);
DISPLAY 0.893617 (-75 2100);
PAINT GREEN (-75 2100);
DISPLAY INVISIBLE (-75 2100);
FORCEPROP 1 LAST SIZE 1B
J 0
(0 1900);
DISPLAY 0.893617 (0 1900);
PAINT GREEN (0 1900);
DISPLAY INVISIBLE (0 1900);
FORCEPROP 1 LAST PATH I10
J 0
(0 1950);
DISPLAY 0.872340 (0 1950);
PAINT AQUA (0 1950);
DISPLAY INVISIBLE (0 1950);
FORCEADD CAP..1
(-75 2200);
FORCEPROP 1 LAST VALUE 10UF
J 0
(-25 2250);
DISPLAY 0.617021 (-25 2250);
PAINT SKYBLUE (-25 2250);
FORCEPROP 1 LASTPIN (-75 2100) $PN 2
J 0
(-65 2080);
DISPLAY 0.617021 (-65 2080);
PAINT WHITE (-65 2080);
FORCEPROP 1 LASTPIN (-75 2300) $PN 1
J 0
(-65 2280);
DISPLAY 0.617021 (-65 2280);
PAINT WHITE (-65 2280);
FORCEPROP 1 LAST MATERIAL X6S
J 0
(-25 2100);
DISPLAY 0.617021 (-25 2100);
PAINT SKYBLUE (-25 2100);
FORCEPROP 1 LAST VOLTAGE 4V
J 0
(-25 2200);
DISPLAY 0.617021 (-25 2200);
PAINT SKYBLUE (-25 2200);
FORCEPROP 1 LAST TOLERANCE 20%
J 0
(-25 2150);
DISPLAY 0.617021 (-25 2150);
PAINT SKYBLUE (-25 2150);
FORCEPROP 1 LAST LOCATION C6U13
J 0
(-25 2300);
DISPLAY 0.617021 (-25 2300);
PAINT AQUA (-25 2300);
FORCEPROP 1 LAST PART_NUMBER E15431-001
J 0
(-25 2050);
DISPLAY 0.617021 (-25 2050);
PAINT BLUE (-25 2050);
FORCEPROP 1 LAST PACK_TYPE 0603LF
J 0
(-25 2000);
DISPLAY 0.617021 (-25 2000);
PAINT SKYBLUE (-25 2000);
FORCEPROP 2 LAST SEC 1
J 0
(-19 2415);
DISPLAY 0.680851 (-19 2415);
PAINT MONO (-19 2415);
DISPLAY INVISIBLE (-19 2415);
FORCEPROP 2 LAST SEC_TYPE 0603LF
J 0
(-19 2415);
DISPLAY 1.021277 (-19 2415);
PAINT ORANGE (-19 2415);
DISPLAY INVISIBLE (-19 2415);
FORCEPROP 2 LAST BOM_COST MEM_VRD_VTT_GHJ
J 0
(-25 2400);
DISPLAY 1.021277 (-25 2400);
PAINT ORANGE (-25 2400);
DISPLAY INVISIBLE (-25 2400);
FORCEPROP 2 LAST ROOM VTT_GHJ_PWR_VR
J 0
(-25 2350);
DISPLAY 1.021277 (-25 2350);
PAINT ORANGE (-25 2350);
DISPLAY INVISIBLE (-25 2350);
FORCEPROP 2 LAST CDS_LOCATION C6U13
J 0
(-25 2300);
DISPLAY 0.617021 (-25 2300);
PAINT AQUA (-25 2300);
DISPLAY INVISIBLE (-25 2300);
FORCEPROP 2 LAST CDS_LIB mstr_discrete
J 0
(-75 2200);
PAINT ORANGE (-75 2200);
DISPLAY INVISIBLE (-75 2200);
FORCEPROP 0 LAST CDS_SEC 1
J 0
(-25 2350);
PAINT MONO (-25 2350);
DISPLAY INVISIBLE (-25 2350);
FORCEPROP 1 LAST PATH I11
J 0
(-25 2350);
DISPLAY 0.978723 (-25 2350);
PAINT WHITE (-25 2350);
DISPLAY INVISIBLE (-25 2350);
FORCEADD SHUNT..1
(4850 -150);
FORCEPROP 1 LASTPIN (5000 -150) $PN 2
J 0
(4960 -140);
DISPLAY 0.617021 (4960 -140);
PAINT ORANGE (4960 -140);
FORCEPROP 1 LAST LOCATION SH8U1
J 0
(4800 -100);
DISPLAY 0.617021 (4800 -100);
PAINT AQUA (4800 -100);
FORCEPROP 1 LAST PART_NUMBER N_A
J 0
(4775 -240);
DISPLAY 0.617021 (4775 -240);
PAINT BLUE (4775 -240);
FORCEPROP 1 LASTPIN (4700 -150) $PN 1
J 2
(4750 -140);
DISPLAY 0.617021 (4750 -140);
PAINT ORANGE (4750 -140);
FORCEPROP 2 LAST SEC_TYPE SH0201
J 0
(4800 0);
DISPLAY 1.021277 (4800 0);
PAINT ORANGE (4800 0);
DISPLAY INVISIBLE (4800 0);
FORCEPROP 2 LAST CDS_LIB mstr_misc
J 0
(4850 -150);
PAINT ORANGE (4850 -150);
DISPLAY INVISIBLE (4850 -150);
FORCEPROP 0 LAST SEC 1
J 0
(4775 -50);
DISPLAY 0.680851 (4775 -50);
PAINT MONO (4775 -50);
DISPLAY INVISIBLE (4775 -50);
FORCEPROP 1 LAST PACK_TYPE SH0201
J 0
(4790 -335);
DISPLAY 0.978723 (4790 -335);
PAINT SKYBLUE (4790 -335);
DISPLAY INVISIBLE (4790 -335);
FORCEPROP 1 LAST PIN_SHORT A:B
J 0
(4775 -400);
DISPLAY 1.021277 (4775 -400);
PAINT ORANGE (4775 -400);
DISPLAY INVISIBLE (4775 -400);
FORCEPROP 1 LAST MATERIAL EMPTY
J 0
(4775 -285);
DISPLAY 0.978723 (4775 -285);
PAINT RED (4775 -285);
DISPLAY INVISIBLE (4775 -285);
FORCEPROP 0 LAST CDS_LOCATION SH8U1
J 0
(4800 -50);
PAINT MONO (4800 -50);
DISPLAY INVISIBLE (4800 -50);
FORCEPROP 0 LAST CDS_SEC 1
J 0
(4800 -50);
PAINT MONO (4800 -50);
DISPLAY INVISIBLE (4800 -50);
FORCEPROP 1 LAST PATH I12
J 0
(4800 -50);
DISPLAY 0.978723 (4800 -50);
PAINT ORANGE (4800 -50);
DISPLAY INVISIBLE (4800 -50);
FORCEADD GND..1
(200 600);
FORCEPROP 3 LASTPIN (200 650) SIG_NAME GND\g
J 0
(210 660);
DISPLAY 0.659574 (210 660);
PAINT MONO (210 660);
DISPLAY INVISIBLE (210 660);
FORCEPROP 1 LAST HDL_POWER GND
J 0
(200 750);
DISPLAY 0.872340 (200 750);
PAINT GREEN (200 750);
DISPLAY INVISIBLE (200 750);
FORCEPROP 2 LAST CDS_LIB mstr_symbols
J 0
(200 600);
PAINT ORANGE (200 600);
DISPLAY INVISIBLE (200 600);
FORCEPROP 1 LAST SIZE 1B
J 0
(275 550);
DISPLAY 0.872340 (275 550);
PAINT AQUA (275 550);
DISPLAY INVISIBLE (275 550);
FORCEPROP 1 LAST BODY_TYPE PLUMBING
J 0
(155 557);
DISPLAY 0.340426 (155 557);
PAINT GREEN (155 557);
DISPLAY INVISIBLE (155 557);
FORCEPROP 1 LAST VOLTAGE 0.0V
J 0
(155 557);
DISPLAY 0.340426 (155 557);
PAINT SKYBLUE (155 557);
DISPLAY INVISIBLE (155 557);
FORCEPROP 1 LAST PATH I13
J 0
(275 600);
DISPLAY 0.872340 (275 600);
PAINT AQUA (275 600);
DISPLAY INVISIBLE (275 600);
FORCEADD CAP..1
(200 825);
FORCEPROP 1 LAST PACK_TYPE 0603
J 0
(250 625);
DISPLAY 0.617021 (250 625);
PAINT SKYBLUE (250 625);
FORCEPROP 1 LAST PART_NUMBER E15431-003
J 0
(250 675);
DISPLAY 0.617021 (250 675);
PAINT BLUE (250 675);
FORCEPROP 1 LAST MATERIAL X6S
J 0
(250 725);
DISPLAY 0.617021 (250 725);
PAINT SKYBLUE (250 725);
FORCEPROP 1 LAST TOLERANCE 10%
J 0
(250 775);
DISPLAY 0.617021 (250 775);
PAINT SKYBLUE (250 775);
FORCEPROP 1 LASTPIN (200 925) $PN 1
J 0
(210 905);
DISPLAY 0.617021 (210 905);
PAINT ORANGE (210 905);
FORCEPROP 1 LAST VOLTAGE 6.3V
J 0
(250 825);
DISPLAY 0.617021 (250 825);
PAINT SKYBLUE (250 825);
FORCEPROP 1 LASTPIN (200 725) $PN 2
J 0
(210 705);
DISPLAY 0.617021 (210 705);
PAINT ORANGE (210 705);
FORCEPROP 1 LAST VALUE 4.7UF
J 0
(250 875);
DISPLAY 0.617021 (250 875);
PAINT SKYBLUE (250 875);
FORCEPROP 1 LAST LOCATION C6U11
J 0
(250 925);
DISPLAY 0.617021 (250 925);
PAINT AQUA (250 925);
FORCEPROP 0 LAST ROOM VTT_GHJ_PWR_VR
J 0
(250 1025);
DISPLAY 1.021277 (250 1025);
PAINT ORANGE (250 1025);
DISPLAY INVISIBLE (250 1025);
FORCEPROP 2 LAST SEC 1
J 0
(250 1025);
DISPLAY 0.680851 (250 1025);
PAINT MONO (250 1025);
DISPLAY INVISIBLE (250 1025);
FORCEPROP 2 LAST SEC_TYPE 0603
J 0
(250 1025);
DISPLAY 1.021277 (250 1025);
PAINT ORANGE (250 1025);
DISPLAY INVISIBLE (250 1025);
FORCEPROP 2 LAST CDS_LOCATION C6U11
J 0
(250 925);
DISPLAY 0.617021 (250 925);
PAINT AQUA (250 925);
DISPLAY INVISIBLE (250 925);
FORCEPROP 2 LAST CDS_LIB mstr_discrete
J 0
(200 825);
PAINT ORANGE (200 825);
DISPLAY INVISIBLE (200 825);
FORCEPROP 0 LAST CDS_SEC 1
J 0
(250 975);
PAINT MONO (250 975);
DISPLAY INVISIBLE (250 975);
FORCEPROP 1 LAST PATH I14
J 0
(250 975);
DISPLAY 0.978723 (250 975);
PAINT WHITE (250 975);
DISPLAY INVISIBLE (250 975);
FORCEADD GND..1
(350 1100);
FORCEPROP 3 LASTPIN (350 1150) SIG_NAME GND\g
J 0
(360 1160);
DISPLAY 0.659574 (360 1160);
PAINT MONO (360 1160);
DISPLAY INVISIBLE (360 1160);
FORCEPROP 1 LAST HDL_POWER GND
J 0
(350 1250);
DISPLAY 0.893617 (350 1250);
PAINT GREEN (350 1250);
DISPLAY INVISIBLE (350 1250);
FORCEPROP 2 LAST CDS_LIB mstr_symbols
J 0
(350 1100);
DISPLAY 0.744681 (350 1100);
PAINT MONO (350 1100);
DISPLAY INVISIBLE (350 1100);
FORCEPROP 1 LAST SIZE 1B
J 0
(425 1050);
DISPLAY 0.893617 (425 1050);
PAINT GREEN (425 1050);
DISPLAY INVISIBLE (425 1050);
FORCEPROP 1 LAST BODY_TYPE PLUMBING
J 0
(305 1057);
DISPLAY 0.340426 (305 1057);
PAINT GREEN (305 1057);
DISPLAY INVISIBLE (305 1057);
FORCEPROP 1 LAST VOLTAGE 0.0V
J 0
(305 1057);
DISPLAY 0.340426 (305 1057);
PAINT SKYBLUE (305 1057);
DISPLAY INVISIBLE (305 1057);
FORCEPROP 1 LAST PATH I15
J 0
(425 1100);
DISPLAY 0.872340 (425 1100);
PAINT AQUA (425 1100);
DISPLAY INVISIBLE (425 1100);
FORCEADD CAP..1
(350 1325);
FORCEPROP 1 LAST VOLTAGE 16V
J 0
(550 1375);
DISPLAY 0.617021 (550 1375);
PAINT SKYBLUE (550 1375);
FORCEPROP 1 LASTPIN (350 1425) $PN 1
J 0
(360 1405);
DISPLAY 0.617021 (360 1405);
PAINT WHITE (360 1405);
FORCEPROP 1 LAST LOCATION C4G18
J 0
(400 1425);
DISPLAY 0.617021 (400 1425);
PAINT AQUA (400 1425);
FORCEPROP 1 LAST VALUE 1.0UF
J 0
(400 1375);
DISPLAY 0.617021 (400 1375);
PAINT SKYBLUE (400 1375);
FORCEPROP 1 LAST TOLERANCE 10%
J 0
(400 1325);
DISPLAY 0.617021 (400 1325);
PAINT SKYBLUE (400 1325);
FORCEPROP 1 LAST MATERIAL X6S
J 0
(525 1325);
DISPLAY 0.617021 (525 1325);
PAINT SKYBLUE (525 1325);
FORCEPROP 1 LAST PART_NUMBER D97712-011
J 0
(400 1275);
DISPLAY 0.617021 (400 1275);
PAINT BLUE (400 1275);
FORCEPROP 1 LAST PACK_TYPE 0402
J 0
(400 1225);
DISPLAY 0.617021 (400 1225);
PAINT SKYBLUE (400 1225);
FORCEPROP 1 LASTPIN (350 1225) $PN 2
J 0
(360 1205);
DISPLAY 0.617021 (360 1205);
PAINT WHITE (360 1205);
FORCEPROP 2 LAST SEC_TYPE 0402
J 0
(400 1521);
DISPLAY 1.021277 (400 1521);
PAINT ORANGE (400 1521);
DISPLAY INVISIBLE (400 1521);
FORCEPROP 2 LAST BOM_COST MEM_VRD_VTT_GHJ
J 0
(400 1525);
DISPLAY 1.021277 (400 1525);
PAINT ORANGE (400 1525);
DISPLAY INVISIBLE (400 1525);
FORCEPROP 2 LAST SEC 1
J 0
(400 1521);
DISPLAY 0.680851 (400 1521);
PAINT MONO (400 1521);
DISPLAY INVISIBLE (400 1521);
FORCEPROP 2 LAST ROOM VTT_GHJ_PWR_VR
J 0
(400 1475);
DISPLAY 1.021277 (400 1475);
PAINT ORANGE (400 1475);
DISPLAY INVISIBLE (400 1475);
FORCEPROP 2 LAST CDS_LOCATION C4G18
J 0
(400 1425);
DISPLAY 0.617021 (400 1425);
PAINT AQUA (400 1425);
DISPLAY INVISIBLE (400 1425);
FORCEPROP 2 LAST CDS_LIB mstr_discrete
J 0
(350 1325);
PAINT ORANGE (350 1325);
DISPLAY INVISIBLE (350 1325);
FORCEPROP 0 LAST CDS_SEC 1
J 0
(400 1475);
PAINT MONO (400 1475);
DISPLAY INVISIBLE (400 1475);
FORCEPROP 1 LAST PATH I16
J 0
(400 1475);
DISPLAY 0.978723 (400 1475);
PAINT WHITE (400 1475);
DISPLAY INVISIBLE (400 1475);
FORCEADD GND..1
(1875 425);
FORCEPROP 3 LASTPIN (1875 475) SIG_NAME GND\g
J 0
(1885 485);
DISPLAY 0.659574 (1885 485);
PAINT MONO (1885 485);
DISPLAY INVISIBLE (1885 485);
FORCEPROP 1 LAST HDL_POWER GND
J 0
(1875 575);
DISPLAY 0.872340 (1875 575);
PAINT GREEN (1875 575);
DISPLAY INVISIBLE (1875 575);
FORCEPROP 1 LAST BODY_TYPE PLUMBING
J 0
(1830 382);
DISPLAY 0.340426 (1830 382);
PAINT GREEN (1830 382);
DISPLAY INVISIBLE (1830 382);
FORCEPROP 2 LAST CDS_LIB mstr_symbols
J 0
(1875 425);
PAINT ORANGE (1875 425);
DISPLAY INVISIBLE (1875 425);
FORCEPROP 1 LAST SIZE 1B
J 0
(1950 375);
DISPLAY 0.872340 (1950 375);
PAINT AQUA (1950 375);
DISPLAY INVISIBLE (1950 375);
FORCEPROP 1 LAST VOLTAGE 0.0V
J 0
(1830 382);
DISPLAY 0.340426 (1830 382);
PAINT SKYBLUE (1830 382);
DISPLAY INVISIBLE (1830 382);
FORCEPROP 1 LAST PATH I17
J 0
(1950 425);
DISPLAY 0.872340 (1950 425);
PAINT AQUA (1950 425);
DISPLAY INVISIBLE (1950 425);
FORCEADD CAP..1
(350 2200);
FORCEPROP 1 LAST TOLERANCE 20%
J 0
(400 2150);
DISPLAY 0.617021 (400 2150);
PAINT SKYBLUE (400 2150);
FORCEPROP 1 LAST PACK_TYPE 0603LF
J 0
(400 2000);
DISPLAY 0.617021 (400 2000);
PAINT SKYBLUE (400 2000);
FORCEPROP 1 LAST VALUE 10UF
J 0
(400 2250);
DISPLAY 0.617021 (400 2250);
PAINT SKYBLUE (400 2250);
FORCEPROP 1 LAST LOCATION C6U14
J 0
(400 2300);
DISPLAY 0.617021 (400 2300);
PAINT AQUA (400 2300);
FORCEPROP 1 LASTPIN (350 2300) $PN 1
J 0
(360 2280);
DISPLAY 0.617021 (360 2280);
PAINT WHITE (360 2280);
FORCEPROP 1 LASTPIN (350 2100) $PN 2
J 0
(360 2080);
DISPLAY 0.617021 (360 2080);
PAINT WHITE (360 2080);
FORCEPROP 1 LAST VOLTAGE 4V
J 0
(400 2200);
DISPLAY 0.617021 (400 2200);
PAINT SKYBLUE (400 2200);
FORCEPROP 1 LAST MATERIAL X6S
J 0
(400 2100);
DISPLAY 0.617021 (400 2100);
PAINT SKYBLUE (400 2100);
FORCEPROP 1 LAST PART_NUMBER E15431-001
J 0
(400 2050);
DISPLAY 0.617021 (400 2050);
PAINT BLUE (400 2050);
FORCEPROP 2 LAST SEC 1
J 0
(406 2415);
DISPLAY 0.680851 (406 2415);
PAINT MONO (406 2415);
DISPLAY INVISIBLE (406 2415);
FORCEPROP 2 LAST BOM_COST MEM_VRD_VTT_GHJ
J 0
(400 2400);
DISPLAY 1.021277 (400 2400);
PAINT ORANGE (400 2400);
DISPLAY INVISIBLE (400 2400);
FORCEPROP 2 LAST SEC_TYPE 0603LF
J 0
(406 2415);
DISPLAY 1.021277 (406 2415);
PAINT ORANGE (406 2415);
DISPLAY INVISIBLE (406 2415);
FORCEPROP 2 LAST ROOM VTT_GHJ_PWR_VR
J 0
(400 2350);
DISPLAY 1.021277 (400 2350);
PAINT ORANGE (400 2350);
DISPLAY INVISIBLE (400 2350);
FORCEPROP 2 LAST CDS_LOCATION C6U14
J 0
(400 2300);
DISPLAY 0.617021 (400 2300);
PAINT AQUA (400 2300);
DISPLAY INVISIBLE (400 2300);
FORCEPROP 2 LAST CDS_LIB mstr_discrete
J 0
(350 2200);
PAINT ORANGE (350 2200);
DISPLAY INVISIBLE (350 2200);
FORCEPROP 0 LAST CDS_SEC 1
J 0
(400 2350);
PAINT MONO (400 2350);
DISPLAY INVISIBLE (400 2350);
FORCEPROP 1 LAST PATH I18
J 0
(400 2350);
DISPLAY 0.978723 (400 2350);
PAINT WHITE (400 2350);
DISPLAY INVISIBLE (400 2350);
FORCEADD GND..1
(350 1950);
FORCEPROP 3 LASTPIN (350 2000) SIG_NAME GND\g
J 0
(360 2010);
DISPLAY 0.659574 (360 2010);
PAINT MONO (360 2010);
DISPLAY INVISIBLE (360 2010);
FORCEPROP 1 LAST HDL_POWER GND
J 0
(350 2100);
DISPLAY 0.893617 (350 2100);
PAINT GREEN (350 2100);
DISPLAY INVISIBLE (350 2100);
FORCEPROP 1 LAST SIZE 1B
J 0
(425 1900);
DISPLAY 0.893617 (425 1900);
PAINT GREEN (425 1900);
DISPLAY INVISIBLE (425 1900);
FORCEPROP 2 LAST CDS_LIB mstr_symbols
J 0
(350 1950);
PAINT MONO (350 1950);
DISPLAY INVISIBLE (350 1950);
FORCEPROP 1 LAST VOLTAGE 0.0V
J 0
(305 1907);
DISPLAY 0.340426 (305 1907);
PAINT SKYBLUE (305 1907);
DISPLAY INVISIBLE (305 1907);
FORCEPROP 1 LAST BODY_TYPE PLUMBING
J 0
(305 1907);
DISPLAY 0.340426 (305 1907);
PAINT GREEN (305 1907);
DISPLAY INVISIBLE (305 1907);
FORCEPROP 2 LAST BOM_COST MEM_VRD_VTT_GHJ
J 0
(-155 2080);
DISPLAY 1.021277 (-155 2080);
PAINT ORANGE (-155 2080);
DISPLAY INVISIBLE (-155 2080);
FORCEPROP 2 LAST ROOM VTT_GHJ_PWR_VR
J 0
(-155 2030);
DISPLAY 1.021277 (-155 2030);
PAINT ORANGE (-155 2030);
DISPLAY INVISIBLE (-155 2030);
FORCEPROP 1 LAST PATH I19
J 0
(425 1950);
DISPLAY 0.872340 (425 1950);
PAINT AQUA (425 1950);
DISPLAY INVISIBLE (425 1950);
FORCEADD CAP..1
R 2
(-475 -550);
FORCEPROP 1 LAST PART_NUMBER A36096-046
J 2
(-525 -750);
DISPLAY 0.659574 (-525 -750);
PAINT BLUE (-525 -750);
FORCEPROP 1 LAST PACK_TYPE 0402LF
J 2
(-525 -644);
DISPLAY 0.617021 (-525 -644);
PAINT SKYBLUE (-525 -644);
FORCEPROP 1 LAST TOLERANCE 10%
J 2
(-550 -600);
DISPLAY 0.617021 (-550 -600);
PAINT SKYBLUE (-550 -600);
FORCEPROP 1 LAST VOLTAGE 50V
J 2
(-575 -550);
DISPLAY 0.617021 (-575 -550);
PAINT SKYBLUE (-575 -550);
FORCEPROP 1 LAST VALUE 1000PF
J 2
(-525 -500);
DISPLAY 0.617021 (-525 -500);
PAINT SKYBLUE (-525 -500);
FORCEPROP 1 LASTPIN (-475 -450) $PN 1
J 2
(-485 -470);
DISPLAY 0.617021 (-485 -470);
PAINT WHITE (-485 -470);
FORCEPROP 1 LASTPIN (-475 -650) $PN 2
J 2
(-485 -670);
DISPLAY 0.617021 (-485 -670);
PAINT WHITE (-485 -670);
FORCEPROP 1 LAST LOCATION C4G12
J 2
(-525 -450);
DISPLAY 0.617021 (-525 -450);
PAINT AQUA (-525 -450);
FORCEPROP 1 LAST MATERIAL EMPTY
J 2
(-529 -688);
DISPLAY 0.617021 (-529 -688);
PAINT RED (-529 -688);
FORCEPROP 2 LAST ROOM VTT_GHJ_PWR_VR
J 0
(-510 -395);
DISPLAY 1.021277 (-510 -395);
PAINT ORANGE (-510 -395);
DISPLAY INVISIBLE (-510 -395);
FORCEPROP 2 LAST SEC 1
J 0
(-504 -330);
DISPLAY 0.680851 (-504 -330);
PAINT MONO (-504 -330);
DISPLAY INVISIBLE (-504 -330);
FORCEPROP 2 LAST BOM_COST MEM_VRD_VTT_GHJ
J 0
(-510 -345);
DISPLAY 1.021277 (-510 -345);
PAINT ORANGE (-510 -345);
DISPLAY INVISIBLE (-510 -345);
FORCEPROP 2 LAST SEC_TYPE 0402LF
J 0
(-504 -330);
DISPLAY 1.021277 (-504 -330);
PAINT ORANGE (-504 -330);
DISPLAY INVISIBLE (-504 -330);
FORCEPROP 2 LAST CDS_LOCATION C4G12
J 2
(-525 -450);
DISPLAY 0.617021 (-525 -450);
PAINT AQUA (-525 -450);
DISPLAY INVISIBLE (-525 -450);
FORCEPROP 2 LAST CDS_LIB mstr_discrete
J 0
(-475 -550);
PAINT ORANGE (-475 -550);
DISPLAY INVISIBLE (-475 -550);
FORCEPROP 0 LAST CDS_SEC 1
J 0
(-525 -400);
PAINT MONO (-525 -400);
DISPLAY INVISIBLE (-525 -400);
FORCEPROP 1 LAST PATH I2
J 2
(-525 -400);
DISPLAY 0.978723 (-525 -400);
PAINT WHITE (-525 -400);
DISPLAY INVISIBLE (-525 -400);
FORCEADD GND..1
(2200 425);
FORCEPROP 3 LASTPIN (2200 475) SIG_NAME GND\g
J 0
(2210 485);
DISPLAY 0.659574 (2210 485);
PAINT MONO (2210 485);
DISPLAY INVISIBLE (2210 485);
FORCEPROP 1 LAST SIZE 1B
J 0
(2275 375);
DISPLAY 0.872340 (2275 375);
PAINT AQUA (2275 375);
DISPLAY INVISIBLE (2275 375);
FORCEPROP 1 LAST HDL_POWER GND
J 0
(2200 575);
DISPLAY 0.872340 (2200 575);
PAINT GREEN (2200 575);
DISPLAY INVISIBLE (2200 575);
FORCEPROP 1 LAST BODY_TYPE PLUMBING
J 0
(2155 382);
DISPLAY 0.340426 (2155 382);
PAINT GREEN (2155 382);
DISPLAY INVISIBLE (2155 382);
FORCEPROP 1 LAST VOLTAGE 0.0V
J 0
(2155 382);
DISPLAY 0.340426 (2155 382);
PAINT SKYBLUE (2155 382);
DISPLAY INVISIBLE (2155 382);
FORCEPROP 2 LAST CDS_LIB mstr_symbols
J 0
(2200 425);
PAINT ORANGE (2200 425);
DISPLAY INVISIBLE (2200 425);
FORCEPROP 1 LAST PATH I20
J 0
(2275 425);
DISPLAY 0.872340 (2275 425);
PAINT AQUA (2275 425);
DISPLAY INVISIBLE (2275 425);
FORCEADD CAP..1
(2200 675);
FORCEPROP 1 LAST PART_NUMBER D97712-011
J 0
(2250 625);
DISPLAY 0.617021 (2250 625);
PAINT BLUE (2250 625);
FORCEPROP 1 LAST PACK_TYPE 0402
J 0
(2250 575);
DISPLAY 0.617021 (2250 575);
PAINT SKYBLUE (2250 575);
FORCEPROP 1 LASTPIN (2200 775) $PN 1
J 0
(2210 755);
DISPLAY 0.617021 (2210 755);
PAINT WHITE (2210 755);
FORCEPROP 1 LASTPIN (2200 575) $PN 2
J 0
(2210 555);
DISPLAY 0.617021 (2210 555);
PAINT WHITE (2210 555);
FORCEPROP 1 LAST MATERIAL X6S
J 0
(2375 675);
DISPLAY 0.617021 (2375 675);
PAINT SKYBLUE (2375 675);
FORCEPROP 1 LAST TOLERANCE 10%
J 0
(2250 675);
DISPLAY 0.617021 (2250 675);
PAINT SKYBLUE (2250 675);
FORCEPROP 1 LAST VOLTAGE 16V
J 0
(2400 725);
DISPLAY 0.617021 (2400 725);
PAINT SKYBLUE (2400 725);
FORCEPROP 1 LAST VALUE 1.0UF
J 0
(2250 725);
DISPLAY 0.617021 (2250 725);
PAINT SKYBLUE (2250 725);
FORCEPROP 1 LAST LOCATION C4G21
J 0
(2250 775);
DISPLAY 0.617021 (2250 775);
PAINT AQUA (2250 775);
FORCEPROP 2 LAST SEC 1
J 0
(2256 890);
DISPLAY 0.680851 (2256 890);
PAINT MONO (2256 890);
DISPLAY INVISIBLE (2256 890);
FORCEPROP 2 LAST SEC_TYPE 0402
J 0
(2256 890);
DISPLAY 1.021277 (2256 890);
PAINT ORANGE (2256 890);
DISPLAY INVISIBLE (2256 890);
FORCEPROP 2 LAST BOM_COST MEM_VRD_VTT_GHJ
J 0
(2250 875);
DISPLAY 1.021277 (2250 875);
PAINT ORANGE (2250 875);
DISPLAY INVISIBLE (2250 875);
FORCEPROP 2 LAST ROOM VTT_GHJ_PWR_VR
J 0
(2250 825);
DISPLAY 1.021277 (2250 825);
PAINT ORANGE (2250 825);
DISPLAY INVISIBLE (2250 825);
FORCEPROP 2 LAST CDS_LOCATION C4G21
J 0
(2250 775);
DISPLAY 0.617021 (2250 775);
PAINT AQUA (2250 775);
DISPLAY INVISIBLE (2250 775);
FORCEPROP 2 LAST CDS_LIB mstr_discrete
J 0
(2200 675);
PAINT ORANGE (2200 675);
DISPLAY INVISIBLE (2200 675);
FORCEPROP 0 LAST CDS_SEC 1
J 0
(2250 825);
PAINT MONO (2250 825);
DISPLAY INVISIBLE (2250 825);
FORCEPROP 1 LAST PATH I21
J 0
(2250 825);
DISPLAY 0.978723 (2250 825);
PAINT WHITE (2250 825);
DISPLAY INVISIBLE (2250 825);
FORCEADD GND..1
(3850 500);
FORCEPROP 3 LASTPIN (3850 550) SIG_NAME GND\g
J 0
(3860 560);
DISPLAY 0.659574 (3860 560);
PAINT MONO (3860 560);
DISPLAY INVISIBLE (3860 560);
FORCEPROP 1 LAST HDL_POWER GND
J 0
(3850 650);
DISPLAY 0.893617 (3850 650);
PAINT GREEN (3850 650);
DISPLAY INVISIBLE (3850 650);
FORCEPROP 1 LAST BODY_TYPE PLUMBING
J 0
(3805 457);
DISPLAY 0.340426 (3805 457);
PAINT GREEN (3805 457);
DISPLAY INVISIBLE (3805 457);
FORCEPROP 2 LAST CDS_LIB mstr_symbols
J 0
(3850 500);
PAINT ORANGE (3850 500);
DISPLAY INVISIBLE (3850 500);
FORCEPROP 1 LAST SIZE 1B
J 0
(3925 450);
DISPLAY 0.893617 (3925 450);
PAINT GREEN (3925 450);
DISPLAY INVISIBLE (3925 450);
FORCEPROP 1 LAST VOLTAGE 0.0V
J 0
(3805 457);
DISPLAY 0.340426 (3805 457);
PAINT SKYBLUE (3805 457);
DISPLAY INVISIBLE (3805 457);
FORCEPROP 1 LAST PATH I22
J 0
(3925 500);
DISPLAY 0.872340 (3925 500);
PAINT AQUA (3925 500);
DISPLAY INVISIBLE (3925 500);
FORCEADD CAP..1
(3850 900);
FORCEPROP 1 LAST LOCATION C4G20
J 0
(3900 1000);
DISPLAY 0.617021 (3900 1000);
PAINT AQUA (3900 1000);
FORCEPROP 1 LAST VALUE 22UF
J 0
(3900 950);
DISPLAY 0.617021 (3900 950);
PAINT SKYBLUE (3900 950);
FORCEPROP 1 LASTPIN (3850 1000) $PN 1
J 0
(3860 980);
DISPLAY 0.617021 (3860 980);
PAINT WHITE (3860 980);
FORCEPROP 1 LASTPIN (3850 800) $PN 2
J 0
(3860 780);
DISPLAY 0.617021 (3860 780);
PAINT WHITE (3860 780);
FORCEPROP 1 LAST PART_NUMBER C95333-002
R 1
J 0
(3800 750);
DISPLAY 0.617021 (3800 750);
PAINT BLUE (3800 750);
FORCEPROP 1 LAST VOLTAGE 4V
J 0
(3900 900);
DISPLAY 0.617021 (3900 900);
PAINT SKYBLUE (3900 900);
FORCEPROP 1 LAST TOLERANCE 20%
J 0
(3900 850);
DISPLAY 0.617021 (3900 850);
PAINT SKYBLUE (3900 850);
FORCEPROP 1 LAST MATERIAL X6S
J 0
(3900 800);
DISPLAY 0.617021 (3900 800);
PAINT SKYBLUE (3900 800);
FORCEPROP 1 LAST PACK_TYPE 0805LF
J 0
(3900 750);
DISPLAY 0.617021 (3900 750);
PAINT SKYBLUE (3900 750);
FORCEPROP 0 LAST GROUP PWR_MLCC_CAP
J 0
(3906 712);
DISPLAY 0.638298 (3906 712);
PAINT BROWN (3906 712);
DISPLAY BOTH (3906 712);
FORCEPROP 2 LAST SEC_TYPE 0805LF
J 0
(3901 1120);
DISPLAY 1.021277 (3901 1120);
PAINT ORANGE (3901 1120);
DISPLAY INVISIBLE (3901 1120);
FORCEPROP 2 LAST SEC 1
J 0
(3901 1120);
DISPLAY 0.680851 (3901 1120);
PAINT MONO (3901 1120);
DISPLAY INVISIBLE (3901 1120);
FORCEPROP 2 LAST BOM_COST MEM_VRD_VTT_GHJ
J 0
(3920 1105);
DISPLAY 1.021277 (3920 1105);
PAINT ORANGE (3920 1105);
DISPLAY INVISIBLE (3920 1105);
FORCEPROP 2 LAST ROOM VTT_GHJ_PWR_VR
J 0
(3920 1055);
DISPLAY 1.021277 (3920 1055);
PAINT ORANGE (3920 1055);
DISPLAY INVISIBLE (3920 1055);
FORCEPROP 2 LAST CDS_LIB mstr_discrete
J 0
(3850 900);
PAINT ORANGE (3850 900);
DISPLAY INVISIBLE (3850 900);
FORCEPROP 2 LAST CDS_LOCATION C4G20
J 0
(3900 1000);
DISPLAY 0.617021 (3900 1000);
PAINT AQUA (3900 1000);
DISPLAY INVISIBLE (3900 1000);
FORCEPROP 0 LAST CDS_SEC 1
J 0
(3900 1050);
PAINT MONO (3900 1050);
DISPLAY INVISIBLE (3900 1050);
FORCEPROP 1 LAST PATH I23
J 0
(3900 1050);
DISPLAY 0.978723 (3900 1050);
PAINT WHITE (3900 1050);
DISPLAY INVISIBLE (3900 1050);
FORCEADD RES..2
(3325 1850);
FORCEPROP 1 LASTPIN (3325 1750) $PN 2
J 0
(3330 1760);
DISPLAY 0.617021 (3330 1760);
PAINT WHITE (3330 1760);
FORCEPROP 1 LAST LOCATION R4G17
J 0
(3370 1975);
DISPLAY 0.617021 (3370 1975);
PAINT AQUA (3370 1975);
FORCEPROP 1 LASTPIN (3325 1950) $PN 1
J 0
(3330 1912);
DISPLAY 0.617021 (3330 1912);
PAINT WHITE (3330 1912);
FORCEPROP 1 LAST PACK_TYPE 0402
J 0
(3515 1825);
DISPLAY 0.617021 (3515 1825);
PAINT SKYBLUE (3515 1825);
FORCEPROP 1 LAST VALUE 10.0K
J 0
(3370 1925);
DISPLAY 0.617021 (3370 1925);
PAINT SKYBLUE (3370 1925);
FORCEPROP 1 LAST TOLERANCE 1%
J 0
(3370 1875);
DISPLAY 0.617021 (3370 1875);
PAINT SKYBLUE (3370 1875);
FORCEPROP 1 LAST WATTAGE 1/16W
J 0
(3365 1825);
DISPLAY 0.617021 (3365 1825);
PAINT SKYBLUE (3365 1825);
FORCEPROP 1 LAST MATERIAL CHIP
J 0
(3365 1775);
DISPLAY 0.617021 (3365 1775);
PAINT SKYBLUE (3365 1775);
FORCEPROP 1 LAST PART_NUMBER G21796-016
J 0
(3365 1725);
DISPLAY 0.617021 (3365 1725);
PAINT BLUE (3365 1725);
FORCEPROP 2 LAST CDS_LOCATION R4G17
J 0
(3370 1975);
DISPLAY 0.617021 (3370 1975);
PAINT AQUA (3370 1975);
DISPLAY INVISIBLE (3370 1975);
FORCEPROP 2 LAST SEC 1
J 0
(3375 2071);
DISPLAY 0.680851 (3375 2071);
PAINT MONO (3375 2071);
DISPLAY INVISIBLE (3375 2071);
FORCEPROP 2 LAST SEC_TYPE 0402
J 0
(3375 2071);
DISPLAY 1.021277 (3375 2071);
PAINT ORANGE (3375 2071);
DISPLAY INVISIBLE (3375 2071);
FORCEPROP 2 LAST BOM_COST MEM_VRD_VTT_GHJ
J 0
(3375 2075);
DISPLAY 1.021277 (3375 2075);
PAINT ORANGE (3375 2075);
DISPLAY INVISIBLE (3375 2075);
FORCEPROP 2 LAST ROOM VTT_GHJ_PWR_VR
J 0
(3375 2025);
DISPLAY 1.021277 (3375 2025);
PAINT ORANGE (3375 2025);
DISPLAY INVISIBLE (3375 2025);
FORCEPROP 2 LAST CDS_LIB mstr_discrete
J 0
(3325 1850);
PAINT ORANGE (3325 1850);
DISPLAY INVISIBLE (3325 1850);
FORCEPROP 0 LAST CDS_SEC 1
J 0
(3375 2025);
PAINT MONO (3375 2025);
DISPLAY INVISIBLE (3375 2025);
FORCEPROP 1 LAST PATH I24
J 0
(3375 2025);
DISPLAY 0.978723 (3375 2025);
PAINT WHITE (3375 2025);
DISPLAY INVISIBLE (3375 2025);
FORCEADD GND..1
(3975 1250);
FORCEPROP 3 LASTPIN (3975 1300) SIG_NAME GND\g
J 0
(3985 1310);
DISPLAY 0.659574 (3985 1310);
PAINT MONO (3985 1310);
DISPLAY INVISIBLE (3985 1310);
FORCEPROP 1 LAST HDL_POWER GND
J 0
(3975 1400);
DISPLAY 0.893617 (3975 1400);
PAINT GREEN (3975 1400);
DISPLAY INVISIBLE (3975 1400);
FORCEPROP 1 LAST SIZE 1B
J 0
(4050 1200);
DISPLAY 0.893617 (4050 1200);
PAINT GREEN (4050 1200);
DISPLAY INVISIBLE (4050 1200);
FORCEPROP 1 LAST BODY_TYPE PLUMBING
J 0
(3930 1207);
DISPLAY 0.340426 (3930 1207);
PAINT GREEN (3930 1207);
DISPLAY INVISIBLE (3930 1207);
FORCEPROP 2 LAST CDS_LIB mstr_symbols
J 0
(3975 1250);
DISPLAY 0.744681 (3975 1250);
PAINT MONO (3975 1250);
DISPLAY INVISIBLE (3975 1250);
FORCEPROP 1 LAST VOLTAGE 0.0V
J 0
(3930 1207);
DISPLAY 0.340426 (3930 1207);
PAINT SKYBLUE (3930 1207);
DISPLAY INVISIBLE (3930 1207);
FORCEPROP 1 LAST PATH I25
J 0
(4050 1250);
DISPLAY 0.872340 (4050 1250);
PAINT AQUA (4050 1250);
DISPLAY INVISIBLE (4050 1250);
FORCEADD CAP..1
R 2
(3975 1450);
FORCEPROP 1 LAST VALUE 1000PF
J 2
(3925 1500);
DISPLAY 0.617021 (3925 1500);
PAINT SKYBLUE (3925 1500);
FORCEPROP 1 LAST TOLERANCE 10%
J 2
(3925 1400);
DISPLAY 0.617021 (3925 1400);
PAINT SKYBLUE (3925 1400);
FORCEPROP 1 LAST PART_NUMBER A36096-046
J 2
(3925 1300);
DISPLAY 0.617021 (3925 1300);
PAINT BLUE (3925 1300);
FORCEPROP 1 LASTPIN (3975 1550) $PN 1
J 2
(3965 1530);
DISPLAY 0.617021 (3965 1530);
PAINT WHITE (3965 1530);
FORCEPROP 1 LASTPIN (3975 1350) $PN 2
J 2
(3965 1330);
DISPLAY 0.617021 (3965 1330);
PAINT WHITE (3965 1330);
FORCEPROP 1 LAST LOCATION C4G13
J 2
(3925 1550);
DISPLAY 0.617021 (3925 1550);
PAINT AQUA (3925 1550);
FORCEPROP 1 LAST VOLTAGE 50V
J 2
(3925 1450);
DISPLAY 0.617021 (3925 1450);
PAINT SKYBLUE (3925 1450);
FORCEPROP 1 LAST MATERIAL X7R
J 2
(3925 1350);
DISPLAY 0.617021 (3925 1350);
PAINT SKYBLUE (3925 1350);
FORCEPROP 1 LAST PACK_TYPE 0402LF
J 2
(3925 1250);
DISPLAY 0.617021 (3925 1250);
PAINT SKYBLUE (3925 1250);
FORCEPROP 2 LAST SEC_TYPE 0402LF
J 2
(3925 1650);
DISPLAY 1.021277 (3925 1650);
PAINT ORANGE (3925 1650);
DISPLAY INVISIBLE (3925 1650);
FORCEPROP 2 LAST BOM_COST MEM_VRD_VTT_GHJ
J 2
(3925 1650);
DISPLAY 1.021277 (3925 1650);
PAINT ORANGE (3925 1650);
DISPLAY INVISIBLE (3925 1650);
FORCEPROP 2 LAST SEC 1
J 2
(3925 1650);
DISPLAY 0.680851 (3925 1650);
PAINT MONO (3925 1650);
DISPLAY INVISIBLE (3925 1650);
FORCEPROP 2 LAST ROOM VTT_GHJ_PWR_VR
J 2
(3925 1600);
DISPLAY 1.021277 (3925 1600);
PAINT ORANGE (3925 1600);
DISPLAY INVISIBLE (3925 1600);
FORCEPROP 2 LAST CDS_LIB mstr_discrete
J 2
(3975 1450);
DISPLAY 0.744681 (3975 1450);
PAINT MONO (3975 1450);
DISPLAY INVISIBLE (3975 1450);
FORCEPROP 2 LAST CDS_LOCATION C4G13
J 2
(3925 1550);
DISPLAY 0.617021 (3925 1550);
PAINT AQUA (3925 1550);
DISPLAY INVISIBLE (3925 1550);
FORCEPROP 0 LAST CDS_SEC 1
J 0
(3925 1600);
PAINT MONO (3925 1600);
DISPLAY INVISIBLE (3925 1600);
FORCEPROP 1 LAST PATH I26
J 2
(3925 1600);
DISPLAY 0.978723 (3925 1600);
PAINT WHITE (3925 1600);
DISPLAY INVISIBLE (3925 1600);
FORCEADD P3V3..1
(3325 2075);
FORCEPROP 3 LASTPIN (3325 2025) SIG_NAME P3V3\g
J 0
(3335 2035);
DISPLAY 0.659574 (3335 2035);
PAINT MONO (3335 2035);
DISPLAY INVISIBLE (3335 2035);
FORCEPROP 2 LAST CDS_LIB mstr_symbols
J 0
(3325 2075);
PAINT ORANGE (3325 2075);
DISPLAY INVISIBLE (3325 2075);
FORCEPROP 1 LAST SIZE 1B
J 0
(3370 2097);
DISPLAY 0.340426 (3370 2097);
PAINT GREEN (3370 2097);
DISPLAY INVISIBLE (3370 2097);
FORCEPROP 1 LAST VOLTAGE 3.3V
J 0
(3280 2032);
DISPLAY 0.340426 (3280 2032);
PAINT SKYBLUE (3280 2032);
DISPLAY INVISIBLE (3280 2032);
FORCEPROP 1 LAST BODY_TYPE PLUMBING
J 0
(3280 2032);
DISPLAY 0.340426 (3280 2032);
PAINT GREEN (3280 2032);
DISPLAY INVISIBLE (3280 2032);
FORCEPROP 1 LAST HDL_POWER P3V3
J 0
(3000 1950);
DISPLAY 0.872340 (3000 1950);
PAINT ORANGE (3000 1950);
DISPLAY INVISIBLE (3000 1950);
FORCEPROP 1 LAST PATH I27
J 0
(3370 2077);
DISPLAY 0.340426 (3370 2077);
PAINT GREEN (3370 2077);
DISPLAY INVISIBLE (3370 2077);
FORCEADD CAP_A..1
(3400 3200);
FORCEPROP 1 LAST MATERIAL X5R
J 0
(3450 3100);
DISPLAY 0.617021 (3450 3100);
PAINT SKYBLUE (3450 3100);
FORCEPROP 1 LAST TOLERANCE 20%
J 0
(3450 3150);
DISPLAY 0.617021 (3450 3150);
PAINT SKYBLUE (3450 3150);
FORCEPROP 1 LAST VOLTAGE 4V
J 0
(3450 3200);
DISPLAY 0.617021 (3450 3200);
PAINT SKYBLUE (3450 3200);
FORCEPROP 1 LASTPIN (3400 3300) $PN 1
J 0
(3410 3280);
DISPLAY 0.617021 (3410 3280);
PAINT ORANGE (3410 3280);
FORCEPROP 1 LASTPIN (3400 3100) $PN 2
J 0
(3410 3080);
DISPLAY 0.617021 (3410 3080);
PAINT ORANGE (3410 3080);
FORCEPROP 1 LAST LOCATION C2F2
J 0
(3450 3300);
DISPLAY 0.617021 (3450 3300);
PAINT AQUA (3450 3300);
FORCEPROP 1 LAST PACK_TYPE 0603V
J 0
(3450 3000);
DISPLAY 0.617021 (3450 3000);
PAINT SKYBLUE (3450 3000);
FORCEPROP 1 LAST PART_NUMBER 602433-106
J 0
(3450 3050);
DISPLAY 0.617021 (3450 3050);
PAINT BLUE (3450 3050);
FORCEPROP 0 LAST GROUP PWR_MLCC_CAP
J 0
(3456 2887);
DISPLAY 0.638298 (3456 2887);
PAINT BROWN (3456 2887);
DISPLAY BOTH (3456 2887);
FORCEPROP 1 LAST VALUE 47UF
J 0
(3450 3250);
DISPLAY 0.617021 (3450 3250);
PAINT SKYBLUE (3450 3250);
FORCEPROP 2 LAST SEC 1
J 0
(3450 3400);
DISPLAY 0.680851 (3450 3400);
PAINT MONO (3450 3400);
DISPLAY INVISIBLE (3450 3400);
FORCEPROP 2 LAST SEC_TYPE 0603V
J 0
(3450 3400);
DISPLAY 1.021277 (3450 3400);
PAINT ORANGE (3450 3400);
DISPLAY INVISIBLE (3450 3400);
FORCEPROP 2 LAST CDS_SEC 1
J 0
(3450 3350);
PAINT ORANGE (3450 3350);
DISPLAY INVISIBLE (3450 3350);
FORCEPROP 2 LAST CDS_LOCATION C2F2
J 0
(3450 3300);
DISPLAY 0.617021 (3450 3300);
PAINT AQUA (3450 3300);
DISPLAY INVISIBLE (3450 3300);
FORCEPROP 2 LAST CDS_LIB dev_discrete
J 0
(3400 3200);
PAINT ORANGE (3400 3200);
DISPLAY INVISIBLE (3400 3200);
FORCEPROP 1 LAST PATH I28
J 0
(3450 3350);
DISPLAY 0.978723 (3450 3350);
PAINT WHITE (3450 3350);
DISPLAY INVISIBLE (3450 3350);
FORCEADD PVTT_GHJ..1
(3400 3475);
FORCEPROP 3 LASTPIN (3400 3425) SIG_NAME PVTT_GHJ\g
J 0
(3410 3435);
DISPLAY 0.659574 (3410 3435);
PAINT MONO (3410 3435);
DISPLAY INVISIBLE (3410 3435);
FORCEPROP 2 LAST ROOM VTT_GHJ_VR
J 0
(3650 3575);
PAINT ORANGE (3650 3575);
DISPLAY INVISIBLE (3650 3575);
FORCEPROP 1 LAST HDL_POWER PVTT_GHJ
J 1
(3400 3525);
DISPLAY 0.872340 (3400 3525);
PAINT GREEN (3400 3525);
DISPLAY INVISIBLE (3400 3525);
FORCEPROP 1 LAST BODY_TYPE PLUMBING
J 0
(3355 3432);
DISPLAY 0.340426 (3355 3432);
PAINT GREEN (3355 3432);
DISPLAY INVISIBLE (3355 3432);
FORCEPROP 2 LAST CDS_LIB mstr_symbols
J 0
(3400 3475);
PAINT ORANGE (3400 3475);
DISPLAY INVISIBLE (3400 3475);
FORCEPROP 2 LAST BOM_COST MEM_VRD_PVDDQ_GHJ
J 0
(3475 3575);
PAINT MONO (3475 3575);
DISPLAY INVISIBLE (3475 3575);
FORCEPROP 1 LAST VOLTAGE 0.6V
J 0
(3355 3432);
DISPLAY 0.340426 (3355 3432);
PAINT SKYBLUE (3355 3432);
DISPLAY INVISIBLE (3355 3432);
FORCEPROP 1 LAST PATH I29
J 0
(3450 3500);
DISPLAY 0.872340 (3450 3500);
PAINT AQUA (3450 3500);
DISPLAY INVISIBLE (3450 3500);
FORCEADD OFFPAGE..1
(-1525 -25);
FORCEPROP 2 LAST $XR0 223 
J 0
(-1777 -25);
DISPLAY 0.638298 (-1777 -25);
PAINT MONO (-1777 -25);
FORCEPROP 2 LAST CDS_LIB mstr_standard
J 0
(-1525 -25);
DISPLAY 0.744681 (-1525 -25);
PAINT MONO (-1525 -25);
DISPLAY INVISIBLE (-1525 -25);
FORCEPROP 1 LAST OFFPAGE TRUE
J 0
(-1200 -150);
DISPLAY 0.872340 (-1200 -150);
PAINT GREEN (-1200 -150);
DISPLAY INVISIBLE (-1200 -150);
FORCEPROP 1 LAST COMMENT_BODY TRUE
J 0
(-1400 -125);
DISPLAY 0.872340 (-1400 -125);
PAINT GREEN (-1400 -125);
DISPLAY INVISIBLE (-1400 -125);
FORCEPROP 2 LAST PATH I3
J 0
(-1775 25);
DISPLAY 1.021277 (-1775 25);
PAINT ORANGE (-1775 25);
DISPLAY INVISIBLE (-1775 25);
FORCEADD RES..1
(4250 1650);
FORCEPROP 1 LAST TOLERANCE 1%
J 0
(4250 1550);
DISPLAY 0.617021 (4250 1550);
PAINT SKYBLUE (4250 1550);
FORCEPROP 1 LASTPIN (4150 1650) $PN 1
J 0
(4162 1662);
DISPLAY 0.617021 (4162 1662);
PAINT ORANGE (4162 1662);
FORCEPROP 1 LAST LOCATION R4G15
J 0
(4200 1700);
DISPLAY 0.617021 (4200 1700);
PAINT AQUA (4200 1700);
FORCEPROP 1 LAST MATERIAL CHIP
J 0
(4250 1500);
DISPLAY 0.617021 (4250 1500);
PAINT SKYBLUE (4250 1500);
FORCEPROP 1 LASTPIN (4350 1650) $PN 2
J 0
(4312 1662);
DISPLAY 0.617021 (4312 1662);
PAINT ORANGE (4312 1662);
FORCEPROP 1 LAST PACK_TYPE 0402
J 0
(4500 1500);
DISPLAY 0.617021 (4500 1500);
PAINT SKYBLUE (4500 1500);
FORCEPROP 1 LAST WATTAGE 1/16W
J 2
(4225 1500);
DISPLAY 0.617021 (4225 1500);
PAINT SKYBLUE (4225 1500);
FORCEPROP 1 LAST VALUE 33.2
J 2
(4225 1550);
DISPLAY 0.617021 (4225 1550);
PAINT SKYBLUE (4225 1550);
FORCEPROP 1 LAST PART_NUMBER G21796-074
J 0
(4200 1750);
DISPLAY 0.617021 (4200 1750);
PAINT BLUE (4200 1750);
FORCEPROP 2 LAST CDS_LOCATION R4G15
J 0
(4200 1700);
DISPLAY 0.617021 (4200 1700);
PAINT AQUA (4200 1700);
DISPLAY INVISIBLE (4200 1700);
FORCEPROP 2 LAST CDS_LIB mstr_discrete
J 0
(4250 1650);
PAINT MONO (4250 1650);
DISPLAY INVISIBLE (4250 1650);
FORCEPROP 2 LAST SEC_TYPE 0402
J 0
(4200 1850);
DISPLAY 1.021277 (4200 1850);
PAINT ORANGE (4200 1850);
DISPLAY INVISIBLE (4200 1850);
FORCEPROP 2 LAST SEC 1
J 0
(4200 1850);
DISPLAY 0.680851 (4200 1850);
PAINT MONO (4200 1850);
DISPLAY INVISIBLE (4200 1850);
FORCEPROP 0 LAST CDS_SEC 1
J 0
(4200 1800);
PAINT MONO (4200 1800);
DISPLAY INVISIBLE (4200 1800);
FORCEPROP 1 LAST PATH I32
J 0
(4200 1800);
DISPLAY 0.978723 (4200 1800);
PAINT WHITE (4200 1800);
DISPLAY INVISIBLE (4200 1800);
FORCEADD OFFPAGE..2
(5075 1650);
FORCEPROP 2 LAST $XR1 190 
J 0
(5384 1650);
DISPLAY 0.638298 (5384 1650);
PAINT MONO (5384 1650);
FORCEPROP 2 LAST $XR0 230 
J 0
(5264 1650);
DISPLAY 0.638298 (5264 1650);
PAINT MONO (5264 1650);
FORCEPROP 1 LAST OFFPAGE TRUE
J 0
(5400 1525);
DISPLAY 0.872340 (5400 1525);
PAINT GREEN (5400 1525);
DISPLAY INVISIBLE (5400 1525);
FORCEPROP 2 LAST CDS_LIB mstr_standard
J 0
(5075 1650);
DISPLAY 0.744681 (5075 1650);
PAINT MONO (5075 1650);
DISPLAY INVISIBLE (5075 1650);
FORCEPROP 1 LAST COMMENT_BODY TRUE
J 0
(5030 1555);
DISPLAY 0.872340 (5030 1555);
PAINT GREEN (5030 1555);
DISPLAY INVISIBLE (5030 1555);
FORCEPROP 2 LAST PATH I33
J 0
(5400 1700);
DISPLAY 1.021277 (5400 1700);
PAINT ORANGE (5400 1700);
DISPLAY INVISIBLE (5400 1700);
FORCEADD PVTT_GHJ..1
(5425 1400);
FORCEPROP 3 LASTPIN (5425 1350) SIG_NAME PVTT_GHJ\g
J 0
(5435 1360);
DISPLAY 0.659574 (5435 1360);
PAINT MONO (5435 1360);
DISPLAY INVISIBLE (5435 1360);
FORCEPROP 2 LAST CDS_LIB mstr_symbols
J 0
(5425 1400);
PAINT ORANGE (5425 1400);
DISPLAY INVISIBLE (5425 1400);
FORCEPROP 1 LAST HDL_POWER PVTT_GHJ
J 1
(5425 1450);
DISPLAY 0.872340 (5425 1450);
PAINT GREEN (5425 1450);
DISPLAY INVISIBLE (5425 1450);
FORCEPROP 1 LAST VOLTAGE 0.6V
J 0
(5380 1357);
DISPLAY 0.340426 (5380 1357);
PAINT SKYBLUE (5380 1357);
DISPLAY INVISIBLE (5380 1357);
FORCEPROP 1 LAST BODY_TYPE PLUMBING
J 0
(5380 1357);
DISPLAY 0.340426 (5380 1357);
PAINT GREEN (5380 1357);
DISPLAY INVISIBLE (5380 1357);
FORCEPROP 1 LAST PATH I34
J 0
(5475 1425);
DISPLAY 0.872340 (5475 1425);
PAINT AQUA (5475 1425);
DISPLAY INVISIBLE (5475 1425);
FORCEADD GND..1
(3400 2875);
FORCEPROP 3 LASTPIN (3400 2925) SIG_NAME GND\g
J 0
(3410 2935);
DISPLAY 0.659574 (3410 2935);
PAINT MONO (3410 2935);
DISPLAY INVISIBLE (3410 2935);
FORCEPROP 1 LAST HDL_POWER GND
J 0
(3400 3025);
DISPLAY 0.893617 (3400 3025);
PAINT GREEN (3400 3025);
DISPLAY INVISIBLE (3400 3025);
FORCEPROP 1 LAST BODY_TYPE PLUMBING
J 0
(3355 2832);
DISPLAY 0.340426 (3355 2832);
PAINT GREEN (3355 2832);
DISPLAY INVISIBLE (3355 2832);
FORCEPROP 1 LAST SIZE 1B
J 0
(3475 2825);
DISPLAY 0.893617 (3475 2825);
PAINT GREEN (3475 2825);
DISPLAY INVISIBLE (3475 2825);
FORCEPROP 2 LAST CDS_LIB mstr_symbols
J 0
(3400 2875);
PAINT ORANGE (3400 2875);
DISPLAY INVISIBLE (3400 2875);
FORCEPROP 1 LAST VOLTAGE 0.0V
J 0
(3355 2832);
DISPLAY 0.340426 (3355 2832);
PAINT SKYBLUE (3355 2832);
DISPLAY INVISIBLE (3355 2832);
FORCEPROP 2 LAST BOM_COST MEM_VRD_PVDDQ_GHJ
J 0
(3075 2950);
PAINT MONO (3075 2950);
DISPLAY INVISIBLE (3075 2950);
FORCEPROP 2 LAST ROOM VTT_GHJ_VR
J 0
(2850 2950);
PAINT ORANGE (2850 2950);
DISPLAY INVISIBLE (2850 2950);
FORCEPROP 1 LAST PATH I35
J 0
(3475 2875);
DISPLAY 0.872340 (3475 2875);
PAINT AQUA (3475 2875);
DISPLAY INVISIBLE (3475 2875);
FORCEADD MIC5166..1
(1425 900);
FORCEPROP 1 LAST LOCATION EU4G2
J 0
(1175 1325);
DISPLAY 0.617021 (1175 1325);
PAINT AQUA (1175 1325);
FORCEPROP 1 LAST MATERIAL IC
J 0
(1175 1275);
DISPLAY 0.617021 (1175 1275);
PAINT SKYBLUE (1175 1275);
FORCEPROP 2 LASTPIN (1725 850) $PN 5
J 0
(1735 860);
DISPLAY 0.617021 (1735 860);
PAINT ORANGE (1735 860);
FORCEPROP 2 LASTPIN (1725 1150) $PN 9
J 0
(1735 1160);
DISPLAY 0.617021 (1735 1160);
PAINT ORANGE (1735 1160);
FORCEPROP 2 LASTPIN (1125 900) $PN 7
J 2
(1115 910);
DISPLAY 0.617021 (1115 910);
PAINT ORANGE (1115 910);
FORCEPROP 2 LASTPIN (1725 700) $PN 3
J 0
(1735 710);
DISPLAY 0.617021 (1735 710);
PAINT ORANGE (1735 710);
FORCEPROP 2 LASTPIN (1725 750) $PN 8
J 0
(1735 760);
DISPLAY 0.617021 (1735 760);
PAINT ORANGE (1735 760);
FORCEPROP 2 LASTPIN (1125 800) $PN 6
J 2
(1115 810);
DISPLAY 0.617021 (1115 810);
PAINT ORANGE (1115 810);
FORCEPROP 2 LASTPIN (1725 1050) $PN 1
J 0
(1735 1060);
DISPLAY 0.617021 (1735 1060);
PAINT ORANGE (1735 1060);
FORCEPROP 2 LASTPIN (1125 650) $PN 2
J 2
(1115 660);
DISPLAY 0.617021 (1115 660);
PAINT ORANGE (1115 660);
FORCEPROP 1 LAST PART_NUMBER H55101-001
J 0
(1175 500);
DISPLAY 0.617021 (1175 500);
PAINT BLUE (1175 500);
FORCEPROP 2 LASTPIN (1125 1000) $PN 4
J 2
(1115 1010);
DISPLAY 0.617021 (1115 1010);
PAINT ORANGE (1115 1010);
FORCEPROP 2 LASTPIN (1725 600) $PN 11
J 0
(1735 610);
DISPLAY 0.617021 (1735 610);
PAINT ORANGE (1735 610);
FORCEPROP 2 LASTPIN (1125 1150) $PN 10
J 2
(1115 1160);
DISPLAY 0.617021 (1115 1160);
PAINT ORANGE (1115 1160);
FORCEPROP 2 LAST SEC 1
J 0
(1190 1382);
DISPLAY 0.680851 (1190 1382);
PAINT MONO (1190 1382);
DISPLAY INVISIBLE (1190 1382);
FORCEPROP 2 LAST BOM_COST MEM_VRD_VTT_GHJ
J 0
(1175 1407);
DISPLAY 1.021277 (1175 1407);
PAINT ORANGE (1175 1407);
DISPLAY INVISIBLE (1175 1407);
FORCEPROP 2 LAST SEC_TYPE DFN
J 0
(1190 1382);
DISPLAY 1.021277 (1190 1382);
PAINT ORANGE (1190 1382);
DISPLAY INVISIBLE (1190 1382);
FORCEPROP 1 LAST PACK_TYPE DFN
J 0
(1175 1375);
PAINT SKYBLUE (1175 1375);
DISPLAY INVISIBLE (1175 1375);
FORCEPROP 2 LAST ROOM VTT_GHJ_PWR_VR
J 0
(1175 1359);
DISPLAY 1.021277 (1175 1359);
PAINT ORANGE (1175 1359);
DISPLAY INVISIBLE (1175 1359);
FORCEPROP 2 LAST CDS_LIB mstr_vreg
J 0
(1425 900);
PAINT ORANGE (1425 900);
DISPLAY INVISIBLE (1425 900);
FORCEPROP 1 LAST CDS_LMAN_SYM_OUTLINE -250,350,250,-350
J 0
(1425 900);
DISPLAY 0.468085 (1425 900);
PAINT GREEN (1425 900);
DISPLAY INVISIBLE (1425 900);
FORCEPROP 2 LAST CDS_LOCATION EU4G2
J 0
(1175 1325);
DISPLAY 0.617021 (1175 1325);
PAINT AQUA (1175 1325);
DISPLAY INVISIBLE (1175 1325);
FORCEPROP 0 LAST CDS_SEC 1
J 0
(1175 1375);
PAINT MONO (1175 1375);
DISPLAY INVISIBLE (1175 1375);
FORCEPROP 1 LAST PATH I37
J 0
(1625 1275);
PAINT GREEN (1625 1275);
DISPLAY INVISIBLE (1625 1275);
FORCEADD RES..1
(-650 -25);
FORCEPROP 1 LAST WATTAGE 1/16W
J 2
(-800 -125);
DISPLAY 0.617021 (-800 -125);
PAINT SKYBLUE (-800 -125);
FORCEPROP 1 LAST VALUE 0.0
J 2
(-675 -125);
DISPLAY 0.617021 (-675 -125);
PAINT SKYBLUE (-675 -125);
FORCEPROP 1 LAST TOLERANCE 5%
J 0
(-650 -125);
DISPLAY 0.617021 (-650 -125);
PAINT SKYBLUE (-650 -125);
FORCEPROP 1 LAST PART_NUMBER G21497-005
J 0
(-823 -82);
DISPLAY 0.617021 (-823 -82);
PAINT BLUE (-823 -82);
FORCEPROP 1 LAST LOCATION R4G16
J 0
(-700 25);
DISPLAY 0.617021 (-700 25);
PAINT AQUA (-700 25);
FORCEPROP 1 LAST MATERIAL CHIP
J 0
(-950 -200);
DISPLAY 0.617021 (-950 -200);
PAINT SKYBLUE (-950 -200);
FORCEPROP 1 LASTPIN (-750 -25) $PN 1
J 0
(-738 -13);
DISPLAY 0.617021 (-738 -13);
PAINT WHITE (-738 -13);
FORCEPROP 1 LAST PACK_TYPE 0402
J 0
(-725 -200);
DISPLAY 0.617021 (-725 -200);
PAINT SKYBLUE (-725 -200);
FORCEPROP 1 LASTPIN (-550 -25) $PN 2
J 0
(-588 -13);
DISPLAY 0.617021 (-588 -13);
PAINT WHITE (-588 -13);
FORCEPROP 2 LAST ROOM VTT_GHJ_PWR_VR
J 0
(-680 130);
DISPLAY 1.021277 (-680 130);
PAINT ORANGE (-680 130);
DISPLAY INVISIBLE (-680 130);
FORCEPROP 2 LAST BOM_COST MEM_VRD_VTT_GHJ
J 0
(-680 180);
DISPLAY 1.021277 (-680 180);
PAINT ORANGE (-680 180);
DISPLAY INVISIBLE (-680 180);
FORCEPROP 2 LAST SEC_TYPE 0402
J 0
(-700 175);
DISPLAY 1.021277 (-700 175);
PAINT ORANGE (-700 175);
DISPLAY INVISIBLE (-700 175);
FORCEPROP 2 LAST SEC 1
J 0
(-700 175);
DISPLAY 0.680851 (-700 175);
PAINT MONO (-700 175);
DISPLAY INVISIBLE (-700 175);
FORCEPROP 2 LAST CDS_LOCATION R4G16
J 0
(-700 25);
DISPLAY 0.617021 (-700 25);
PAINT AQUA (-700 25);
DISPLAY INVISIBLE (-700 25);
FORCEPROP 2 LAST CDS_LIB mstr_discrete
J 0
(-650 -25);
PAINT ORANGE (-650 -25);
DISPLAY INVISIBLE (-650 -25);
FORCEPROP 0 LAST CDS_SEC 1
J 0
(-700 75);
PAINT MONO (-700 75);
DISPLAY INVISIBLE (-700 75);
FORCEPROP 1 LAST PATH I4
J 0
(-700 125);
DISPLAY 0.978723 (-700 125);
PAINT WHITE (-700 125);
DISPLAY INVISIBLE (-700 125);
FORCEADD CAP..1
(3800 3200);
FORCEPROP 1 LAST LOCATION C8T3
J 0
(3850 3300);
DISPLAY 0.617021 (3850 3300);
PAINT AQUA (3850 3300);
FORCEPROP 1 LAST PACK_TYPE 0805
J 0
(3850 3050);
DISPLAY 0.617021 (3850 3050);
PAINT SKYBLUE (3850 3050);
FORCEPROP 1 LAST VALUE 100UF
J 0
(3850 3250);
DISPLAY 0.617021 (3850 3250);
PAINT SKYBLUE (3850 3250);
FORCEPROP 1 LAST VOLTAGE 4V
J 0
(3850 3200);
DISPLAY 0.617021 (3850 3200);
PAINT SKYBLUE (3850 3200);
FORCEPROP 1 LASTPIN (3800 3100) $PN 2
J 0
(3810 3080);
DISPLAY 0.617021 (3810 3080);
PAINT ORANGE (3810 3080);
FORCEPROP 1 LASTPIN (3800 3300) $PN 1
J 0
(3810 3280);
DISPLAY 0.617021 (3810 3280);
PAINT ORANGE (3810 3280);
FORCEPROP 1 LAST TOLERANCE 20%
J 0
(3850 3150);
DISPLAY 0.617021 (3850 3150);
PAINT SKYBLUE (3850 3150);
FORCEPROP 0 LAST NEW_MATERIAL X6S
J 0
(3850 2950);
DISPLAY 0.638298 (3850 2950);
PAINT BROWN (3850 2950);
DISPLAY BOTH (3850 2950);
FORCEPROP 1 LAST PART_NUMBER 602433-112
J 0
(3850 3100);
DISPLAY 0.617021 (3850 3100);
PAINT BLUE (3850 3100);
FORCEPROP 0 LAST GROUP PWR_MLCC_CAP
J 0
(3856 2912);
DISPLAY 0.638298 (3856 2912);
PAINT BROWN (3856 2912);
DISPLAY BOTH (3856 2912);
FORCEPROP 0 LAST NEW_PN 078.1071T.M002
J 0
(3862 3008);
DISPLAY 0.638298 (3862 3008);
PAINT BROWN (3862 3008);
DISPLAY BOTH (3862 3008);
FORCEPROP 1 LAST PATH I41
J 0
(3850 3350);
DISPLAY 0.978723 (3850 3350);
PAINT WHITE (3850 3350);
DISPLAY INVISIBLE (3850 3350);
FORCEPROP 1 LAST MATERIAL X5R
J 0
(3850 3100);
DISPLAY 0.617021 (3850 3100);
PAINT SKYBLUE (3850 3100);
DISPLAY INVISIBLE (3850 3100);
FORCEPROP 2 LAST SEC 1
J 0
(3850 3400);
DISPLAY 0.680851 (3850 3400);
PAINT MONO (3850 3400);
DISPLAY INVISIBLE (3850 3400);
FORCEPROP 2 LAST SEC_TYPE 0805
J 0
(3850 3400);
DISPLAY 1.021277 (3850 3400);
PAINT ORANGE (3850 3400);
DISPLAY INVISIBLE (3850 3400);
FORCEPROP 2 LAST ROOM VDDQ_ABC_PWR_VR
J 0
(3850 3350);
PAINT MONO (3850 3350);
DISPLAY INVISIBLE (3850 3350);
FORCEPROP 2 LAST BOM_COST MEM_VRD_PVDDQ_CD
J 0
(3850 3350);
PAINT MONO (3850 3350);
DISPLAY INVISIBLE (3850 3350);
FORCEPROP 2 LAST CDS_LIB mstr_discrete
J 0
(3800 3200);
PAINT MONO (3800 3200);
DISPLAY INVISIBLE (3800 3200);
FORCEPROP 0 LAST CDS_SEC 1
J 0
(3850 3350);
PAINT MONO (3850 3350);
DISPLAY INVISIBLE (3850 3350);
FORCEPROP 2 LAST CDS_LOCATION C8T3
J 0
(3850 3300);
DISPLAY 0.617021 (3850 3300);
PAINT AQUA (3850 3300);
DISPLAY INVISIBLE (3850 3300);
FORCEADD CAP..1
(4150 3200);
FORCEPROP 1 LAST VOLTAGE 4V
J 0
(4200 3200);
DISPLAY 0.617021 (4200 3200);
PAINT SKYBLUE (4200 3200);
FORCEPROP 1 LASTPIN (4150 3300) $PN 1
J 0
(4160 3280);
DISPLAY 0.617021 (4160 3280);
PAINT ORANGE (4160 3280);
FORCEPROP 1 LASTPIN (4150 3100) $PN 2
J 0
(4160 3080);
DISPLAY 0.617021 (4160 3080);
PAINT ORANGE (4160 3080);
FORCEPROP 1 LAST PART_NUMBER 602433-112
J 0
(4200 3100);
DISPLAY 0.617021 (4200 3100);
PAINT BLUE (4200 3100);
FORCEPROP 1 LAST PACK_TYPE 0805
J 0
(4200 3050);
DISPLAY 0.617021 (4200 3050);
PAINT SKYBLUE (4200 3050);
FORCEPROP 1 LAST VALUE 100UF
J 0
(4200 3250);
DISPLAY 0.617021 (4200 3250);
PAINT SKYBLUE (4200 3250);
FORCEPROP 1 LAST TOLERANCE 20%
J 0
(4200 3150);
DISPLAY 0.617021 (4200 3150);
PAINT SKYBLUE (4200 3150);
FORCEPROP 1 LAST LOCATION C8U10
J 0
(4200 3300);
DISPLAY 0.617021 (4200 3300);
PAINT AQUA (4200 3300);
FORCEPROP 0 LAST GROUP PWR_MLCC_CAP
J 0
(4206 2812);
DISPLAY 0.638298 (4206 2812);
PAINT BROWN (4206 2812);
DISPLAY BOTH (4206 2812);
FORCEPROP 0 LAST NEW_MATERIAL X6S
J 0
(4200 2850);
DISPLAY 0.638298 (4200 2850);
PAINT BROWN (4200 2850);
DISPLAY BOTH (4200 2850);
FORCEPROP 0 LAST NEW_PN 078.1071T.M002
J 0
(4201 2894);
DISPLAY 0.638298 (4201 2894);
PAINT BROWN (4201 2894);
DISPLAY BOTH (4201 2894);
FORCEPROP 1 LAST PATH I42
J 0
(4200 3350);
DISPLAY 0.978723 (4200 3350);
PAINT WHITE (4200 3350);
DISPLAY INVISIBLE (4200 3350);
FORCEPROP 0 LAST CDS_SEC 1
J 0
(4200 3350);
PAINT MONO (4200 3350);
DISPLAY INVISIBLE (4200 3350);
FORCEPROP 2 LAST CDS_LIB mstr_discrete
J 0
(4150 3200);
PAINT MONO (4150 3200);
DISPLAY INVISIBLE (4150 3200);
FORCEPROP 2 LAST BOM_COST MEM_VRD_PVDDQ_CD
J 0
(4200 3350);
PAINT MONO (4200 3350);
DISPLAY INVISIBLE (4200 3350);
FORCEPROP 2 LAST ROOM VDDQ_ABC_PWR_VR
J 0
(4200 3350);
PAINT MONO (4200 3350);
DISPLAY INVISIBLE (4200 3350);
FORCEPROP 2 LAST SEC_TYPE 0805
J 0
(4200 3400);
DISPLAY 1.021277 (4200 3400);
PAINT ORANGE (4200 3400);
DISPLAY INVISIBLE (4200 3400);
FORCEPROP 2 LAST SEC 1
J 0
(4200 3400);
DISPLAY 0.680851 (4200 3400);
PAINT MONO (4200 3400);
DISPLAY INVISIBLE (4200 3400);
FORCEPROP 1 LAST MATERIAL X5R
J 0
(4200 3100);
DISPLAY 0.617021 (4200 3100);
PAINT SKYBLUE (4200 3100);
DISPLAY INVISIBLE (4200 3100);
FORCEPROP 2 LAST CDS_LOCATION C8U10
J 0
(4200 3300);
DISPLAY 0.617021 (4200 3300);
PAINT AQUA (4200 3300);
DISPLAY INVISIBLE (4200 3300);
FORCEADD CAP..1
(4700 900);
FORCEPROP 1 LAST PACK_TYPE 0805
J 0
(4750 750);
DISPLAY 0.617021 (4750 750);
PAINT SKYBLUE (4750 750);
FORCEPROP 1 LAST TOLERANCE 20%
J 0
(4750 850);
DISPLAY 0.617021 (4750 850);
PAINT SKYBLUE (4750 850);
FORCEPROP 1 LASTPIN (4700 800) $PN 2
J 0
(4710 780);
DISPLAY 0.617021 (4710 780);
PAINT ORANGE (4710 780);
FORCEPROP 1 LASTPIN (4700 1000) $PN 1
J 0
(4710 980);
DISPLAY 0.617021 (4710 980);
PAINT ORANGE (4710 980);
FORCEPROP 1 LAST LOCATION C6W12
J 0
(4750 1000);
DISPLAY 0.617021 (4750 1000);
PAINT AQUA (4750 1000);
FORCEPROP 1 LAST VOLTAGE 4V
J 0
(4750 900);
DISPLAY 0.617021 (4750 900);
PAINT SKYBLUE (4750 900);
FORCEPROP 0 LAST NEW_MATERIAL X6S
J 0
(4750 650);
DISPLAY 0.638298 (4750 650);
PAINT BROWN (4750 650);
DISPLAY BOTH (4750 650);
FORCEPROP 1 LAST PART_NUMBER 602433-112
J 0
(4750 800);
DISPLAY 0.617021 (4750 800);
PAINT BLUE (4750 800);
FORCEPROP 1 LAST VALUE 100UF
J 0
(4750 950);
DISPLAY 0.617021 (4750 950);
PAINT SKYBLUE (4750 950);
FORCEPROP 0 LAST GROUP PWR_MLCC_CAP
J 0
(4756 612);
DISPLAY 0.638298 (4756 612);
PAINT BROWN (4756 612);
DISPLAY BOTH (4756 612);
FORCEPROP 0 LAST NEW_PN 078.1071T.M002
J 0
(4748 705);
DISPLAY 0.638298 (4748 705);
PAINT BROWN (4748 705);
DISPLAY BOTH (4748 705);
FORCEPROP 1 LAST MATERIAL X5R
J 0
(4750 800);
DISPLAY 0.617021 (4750 800);
PAINT SKYBLUE (4750 800);
DISPLAY INVISIBLE (4750 800);
FORCEPROP 2 LAST SEC 1
J 0
(4750 1100);
DISPLAY 0.680851 (4750 1100);
PAINT MONO (4750 1100);
DISPLAY INVISIBLE (4750 1100);
FORCEPROP 2 LAST SEC_TYPE 0805
J 0
(4750 1100);
DISPLAY 1.021277 (4750 1100);
PAINT ORANGE (4750 1100);
DISPLAY INVISIBLE (4750 1100);
FORCEPROP 2 LAST ROOM VDDQ_ABC_PWR_VR
J 0
(4750 1050);
PAINT MONO (4750 1050);
DISPLAY INVISIBLE (4750 1050);
FORCEPROP 2 LAST BOM_COST MEM_VRD_PVDDQ_CD
J 0
(4750 1050);
PAINT MONO (4750 1050);
DISPLAY INVISIBLE (4750 1050);
FORCEPROP 2 LAST CDS_LIB mstr_discrete
J 0
(4700 900);
PAINT MONO (4700 900);
DISPLAY INVISIBLE (4700 900);
FORCEPROP 0 LAST CDS_SEC 1
J 0
(4750 1050);
PAINT MONO (4750 1050);
DISPLAY INVISIBLE (4750 1050);
FORCEPROP 1 LAST PATH I43
J 0
(4750 1050);
DISPLAY 0.978723 (4750 1050);
PAINT WHITE (4750 1050);
DISPLAY INVISIBLE (4750 1050);
FORCEPROP 2 LAST CDS_LOCATION C6W12
J 0
(4750 1000);
DISPLAY 0.617021 (4750 1000);
PAINT AQUA (4750 1000);
DISPLAY INVISIBLE (4750 1000);
FORCEADD RES..2
R 2
(-425 500);
FORCEPROP 1 LAST PACK_TYPE 0402
J 2
(-465 325);
DISPLAY 0.617021 (-465 325);
PAINT SKYBLUE (-465 325);
FORCEPROP 1 LAST PART_NUMBER G21796-021
J 2
(-465 375);
DISPLAY 0.617021 (-465 375);
PAINT BLUE (-465 375);
FORCEPROP 1 LAST MATERIAL EMPTY
J 2
(-465 425);
DISPLAY 0.617021 (-465 425);
PAINT RED (-465 425);
FORCEPROP 1 LAST WATTAGE 1/16W
J 2
(-465 475);
DISPLAY 0.617021 (-465 475);
PAINT SKYBLUE (-465 475);
FORCEPROP 1 LAST TOLERANCE 1%
J 2
(-470 525);
DISPLAY 0.617021 (-470 525);
PAINT SKYBLUE (-470 525);
FORCEPROP 1 LASTPIN (-425 600) $PN 1
J 2
(-430 562);
DISPLAY 0.617021 (-430 562);
PAINT WHITE (-430 562);
FORCEPROP 1 LASTPIN (-425 400) $PN 2
J 2
(-430 410);
DISPLAY 0.617021 (-430 410);
PAINT WHITE (-430 410);
FORCEPROP 1 LAST VALUE 1.0M
J 2
(-470 575);
DISPLAY 0.617021 (-470 575);
PAINT SKYBLUE (-470 575);
FORCEPROP 1 LAST LOCATION R6U3
J 2
(-470 625);
DISPLAY 0.617021 (-470 625);
PAINT AQUA (-470 625);
FORCEPROP 2 LAST ROOM VTT_GHJ_PWR_VR
J 0
(-460 665);
DISPLAY 1.021277 (-460 665);
PAINT ORANGE (-460 665);
DISPLAY INVISIBLE (-460 665);
FORCEPROP 2 LAST CDS_LOCATION R6U3
J 2
(-470 625);
DISPLAY 0.617021 (-470 625);
PAINT AQUA (-470 625);
DISPLAY INVISIBLE (-470 625);
FORCEPROP 2 LAST SEC 1
J 0
(-454 730);
DISPLAY 0.680851 (-454 730);
PAINT MONO (-454 730);
DISPLAY INVISIBLE (-454 730);
FORCEPROP 2 LAST SEC_TYPE 0402
J 0
(-454 730);
DISPLAY 1.021277 (-454 730);
PAINT ORANGE (-454 730);
DISPLAY INVISIBLE (-454 730);
FORCEPROP 2 LAST BOM_COST MEM_VRD_VTT_GHJ
J 0
(-460 715);
DISPLAY 1.021277 (-460 715);
PAINT ORANGE (-460 715);
DISPLAY INVISIBLE (-460 715);
FORCEPROP 2 LAST CDS_LIB mstr_discrete
J 0
(-425 500);
PAINT ORANGE (-425 500);
DISPLAY INVISIBLE (-425 500);
FORCEPROP 0 LAST CDS_SEC 1
J 0
(-450 675);
PAINT MONO (-450 675);
DISPLAY INVISIBLE (-450 675);
FORCEPROP 1 LAST PATH I5
J 2
(-475 675);
DISPLAY 0.978723 (-475 675);
PAINT WHITE (-475 675);
DISPLAY INVISIBLE (-475 675);
FORCEADD RES..2
R 1
(-850 1400);
FORCEPROP 1 LASTPIN (-750 1400) $PN 2
R 1
J 0
(-760 1405);
DISPLAY 0.617021 (-760 1405);
PAINT WHITE (-760 1405);
FORCEPROP 1 LASTPIN (-950 1400) $PN 1
R 1
J 0
(-912 1405);
DISPLAY 0.617021 (-912 1405);
PAINT WHITE (-912 1405);
FORCEPROP 1 LAST LOCATION R6U6
J 0
(-900 1520);
DISPLAY 0.617021 (-900 1520);
PAINT AQUA (-900 1520);
FORCEPROP 1 LAST TOLERANCE 5%
J 0
(-1000 1345);
DISPLAY 0.617021 (-1000 1345);
PAINT SKYBLUE (-1000 1345);
FORCEPROP 1 LAST VALUE 0.0
J 0
(-925 1345);
DISPLAY 0.617021 (-925 1345);
PAINT SKYBLUE (-925 1345);
FORCEPROP 1 LAST PACK_TYPE 0402
J 0
(-625 1340);
DISPLAY 0.617021 (-625 1340);
PAINT SKYBLUE (-625 1340);
FORCEPROP 1 LAST MATERIAL CHIP
J 0
(-725 1465);
DISPLAY 0.638298 (-725 1465);
PAINT SKYBLUE (-725 1465);
FORCEPROP 1 LAST WATTAGE 1/16W
J 0
(-825 1340);
DISPLAY 0.617021 (-825 1340);
PAINT SKYBLUE (-825 1340);
FORCEPROP 1 LAST PART_NUMBER G21497-005
J 0
(-950 1290);
DISPLAY 0.617021 (-950 1290);
PAINT BLUE (-950 1290);
FORCEPROP 2 LAST ROOM VTT_GHJ_PWR_VR
J 0
(-875 1500);
DISPLAY 1.021277 (-875 1500);
PAINT ORANGE (-875 1500);
DISPLAY INVISIBLE (-875 1500);
FORCEPROP 2 LAST NO_XNET_CONNECTION 1
J 0
(-900 1550);
PAINT MONO (-900 1550);
DISPLAY INVISIBLE (-900 1550);
FORCEPROP 2 LAST CDS_LOCATION R6U6
J 0
(-900 1520);
DISPLAY 0.617021 (-900 1520);
PAINT AQUA (-900 1520);
DISPLAY INVISIBLE (-900 1520);
FORCEPROP 2 LAST SEC 1
J 0
(-869 1490);
DISPLAY 0.680851 (-869 1490);
PAINT MONO (-869 1490);
DISPLAY INVISIBLE (-869 1490);
FORCEPROP 2 LAST SEC_TYPE 0402
J 0
(-869 1490);
DISPLAY 1.021277 (-869 1490);
PAINT ORANGE (-869 1490);
DISPLAY INVISIBLE (-869 1490);
FORCEPROP 2 LAST BOM_COST MEM_VRD_VTT_GHJ
J 0
(-875 1550);
DISPLAY 1.021277 (-875 1550);
PAINT ORANGE (-875 1550);
DISPLAY INVISIBLE (-875 1550);
FORCEPROP 2 LAST CDS_LIB mstr_discrete
R 1
J 0
(-850 1400);
PAINT ORANGE (-850 1400);
DISPLAY INVISIBLE (-850 1400);
FORCEPROP 0 LAST CDS_SEC 1
R 1
J 0
(-900 1550);
PAINT MONO (-900 1550);
DISPLAY INVISIBLE (-900 1550);
FORCEPROP 1 LAST PATH I6
R 1
J 0
(-1025 1450);
DISPLAY 0.978723 (-1025 1450);
PAINT WHITE (-1025 1450);
DISPLAY INVISIBLE (-1025 1450);
FORCEADD P3V3..1
(-600 1900);
FORCEPROP 3 LASTPIN (-600 1850) SIG_NAME P3V3\g
J 0
(-590 1860);
DISPLAY 0.659574 (-590 1860);
PAINT MONO (-590 1860);
DISPLAY INVISIBLE (-590 1860);
FORCEPROP 2 LAST CDS_LIB mstr_symbols
J 0
(-600 1900);
PAINT ORANGE (-600 1900);
DISPLAY INVISIBLE (-600 1900);
FORCEPROP 1 LAST SIZE 1B
J 0
(-555 1922);
DISPLAY 0.340426 (-555 1922);
PAINT GREEN (-555 1922);
DISPLAY INVISIBLE (-555 1922);
FORCEPROP 1 LAST VOLTAGE 3.3V
J 0
(-645 1857);
DISPLAY 0.340426 (-645 1857);
PAINT SKYBLUE (-645 1857);
DISPLAY INVISIBLE (-645 1857);
FORCEPROP 1 LAST BODY_TYPE PLUMBING
J 0
(-645 1857);
DISPLAY 0.340426 (-645 1857);
PAINT GREEN (-645 1857);
DISPLAY INVISIBLE (-645 1857);
FORCEPROP 1 LAST HDL_POWER P3V3
J 0
(-925 1775);
DISPLAY 0.872340 (-925 1775);
PAINT ORANGE (-925 1775);
DISPLAY INVISIBLE (-925 1775);
FORCEPROP 1 LAST PATH I7
J 0
(-555 1902);
DISPLAY 0.340426 (-555 1902);
PAINT GREEN (-555 1902);
DISPLAY INVISIBLE (-555 1902);
FORCEADD PVDDQ_GHJ..1
(-1550 2625);
FORCEPROP 3 LASTPIN (-1550 2575) SIG_NAME PVDDQ_GHJ\g
J 0
(-1540 2585);
DISPLAY 0.659574 (-1540 2585);
PAINT MONO (-1540 2585);
DISPLAY INVISIBLE (-1540 2585);
FORCEPROP 1 LAST VOLTAGE 1.2V
J 0
(-1595 2582);
DISPLAY 0.340426 (-1595 2582);
PAINT SKYBLUE (-1595 2582);
DISPLAY INVISIBLE (-1595 2582);
FORCEPROP 2 LAST CDS_LIB mstr_symbols
J 0
(-1550 2625);
PAINT ORANGE (-1550 2625);
DISPLAY INVISIBLE (-1550 2625);
FORCEPROP 1 LAST BODY_TYPE PLUMBING
J 0
(-1595 2582);
DISPLAY 0.340426 (-1595 2582);
PAINT GREEN (-1595 2582);
DISPLAY INVISIBLE (-1595 2582);
FORCEPROP 1 LAST HDL_POWER PVDDQ_GHJ
J 1
(-1550 2675);
DISPLAY 0.872340 (-1550 2675);
PAINT GREEN (-1550 2675);
DISPLAY INVISIBLE (-1550 2675);
FORCEPROP 1 LAST PATH I8
J 0
(-1500 2650);
DISPLAY 0.872340 (-1500 2650);
PAINT AQUA (-1500 2650);
DISPLAY INVISIBLE (-1500 2650);
FORCEADD RES..1
(25 1600);
FORCEPROP 1 LASTPIN (125 1600) $PN 2
J 0
(87 1612);
DISPLAY 0.617021 (87 1612);
PAINT WHITE (87 1612);
FORCEPROP 1 LASTPIN (-75 1600) $PN 1
J 0
(-63 1612);
DISPLAY 0.617021 (-63 1612);
PAINT WHITE (-63 1612);
FORCEPROP 1 LAST LOCATION R6U7
J 0
(-25 1650);
DISPLAY 0.617021 (-25 1650);
PAINT AQUA (-25 1650);
FORCEPROP 1 LAST PART_NUMBER G21497-005
J 0
(-100 1550);
DISPLAY 0.617021 (-100 1550);
PAINT BLUE (-100 1550);
FORCEPROP 1 LAST VALUE 0.0
J 2
(0 1500);
DISPLAY 0.617021 (0 1500);
PAINT SKYBLUE (0 1500);
FORCEPROP 1 LAST TOLERANCE 5%
J 0
(25 1500);
DISPLAY 0.617021 (25 1500);
PAINT SKYBLUE (25 1500);
FORCEPROP 1 LAST MATERIAL CHIP
J 0
(25 1450);
DISPLAY 0.617021 (25 1450);
PAINT SKYBLUE (25 1450);
FORCEPROP 1 LAST WATTAGE 1/16W
J 2
(0 1450);
DISPLAY 0.617021 (0 1450);
PAINT SKYBLUE (0 1450);
FORCEPROP 1 LAST PACK_TYPE 0402
J 0
(-50 1400);
DISPLAY 0.617021 (-50 1400);
PAINT SKYBLUE (-50 1400);
FORCEPROP 2 LAST ROOM VTT_GHJ_PWR_VR
J 0
(-15 1685);
DISPLAY 1.021277 (-15 1685);
PAINT ORANGE (-15 1685);
DISPLAY INVISIBLE (-15 1685);
FORCEPROP 2 LAST CDS_LOCATION R6U7
J 0
(-25 1650);
DISPLAY 0.617021 (-25 1650);
PAINT AQUA (-25 1650);
DISPLAY INVISIBLE (-25 1650);
FORCEPROP 2 LAST SEC 1
J 0
(-9 1800);
DISPLAY 0.680851 (-9 1800);
PAINT MONO (-9 1800);
DISPLAY INVISIBLE (-9 1800);
FORCEPROP 2 LAST SEC_TYPE 0402
J 0
(-9 1800);
DISPLAY 1.021277 (-9 1800);
PAINT ORANGE (-9 1800);
DISPLAY INVISIBLE (-9 1800);
FORCEPROP 2 LAST BOM_COST MEM_VRD_VTT_GHJ
J 0
(-15 1735);
DISPLAY 1.021277 (-15 1735);
PAINT ORANGE (-15 1735);
DISPLAY INVISIBLE (-15 1735);
FORCEPROP 2 LAST CDS_LIB mstr_discrete
J 0
(25 1600);
DISPLAY 0.744681 (25 1600);
PAINT MONO (25 1600);
DISPLAY INVISIBLE (25 1600);
FORCEPROP 0 LAST CDS_SEC 1
J 0
(-25 1700);
PAINT MONO (-25 1700);
DISPLAY INVISIBLE (-25 1700);
FORCEPROP 1 LAST PATH I9
J 0
(-25 1750);
DISPLAY 0.978723 (-25 1750);
PAINT WHITE (-25 1750);
DISPLAY INVISIBLE (-25 1750);
FORCEADD CAD_NOTE..1
(4625 -425);
FORCEPROP 0 LAST L1 PLACE NEAR CENTER
J 0
(4507 -520);
DISPLAY 0.617021 (4507 -520);
PAINT WHITE (4507 -520);
FORCEPROP 0 LAST L2 OF PVTT PLANE
J 0
(4507 -572);
DISPLAY 0.617021 (4507 -572);
PAINT WHITE (4507 -572);
FORCEPROP 1 LAST COMMENT_BODY TRUE
J 0
(4650 -325);
DISPLAY 0.978723 (4650 -325);
PAINT ORANGE (4650 -325);
DISPLAY INVISIBLE (4650 -325);
FORCEPROP 2 LAST CDS_LIB mstr_symbols
J 0
(4625 -425);
PAINT ORANGE (4625 -425);
DISPLAY INVISIBLE (4625 -425);
FORCEADD CAD_NOTE..1
(2150 1400);
FORCEPROP 0 LAST L1 PLACE CLOSE TO CONTROLLER
J 0
(1968 1308);
DISPLAY 0.617021 (1968 1308);
PAINT WHITE (1968 1308);
FORCEPROP 1 LAST COMMENT_BODY TRUE
J 0
(2175 1500);
DISPLAY 0.978723 (2175 1500);
PAINT ORANGE (2175 1500);
DISPLAY INVISIBLE (2175 1500);
FORCEPROP 2 LAST CDS_LIB mstr_symbols
J 0
(2150 1400);
PAINT ORANGE (2150 1400);
DISPLAY INVISIBLE (2150 1400);
FORCEADD DNS..2
(-470 -555);
PAINT RED (-470 -555);
FORCEPROP 2 LAST CDS_LIB mstr_misc
J 0
(-470 -555);
PAINT ORANGE (-470 -555);
DISPLAY INVISIBLE (-470 -555);
FORCEPROP 1 LAST COMMENT_BODY TRUE
R 1
J 0
(-395 -780);
DISPLAY 0.872340 (-395 -780);
PAINT GREEN (-395 -780);
DISPLAY INVISIBLE (-395 -780);
FORCEADD CAD_NOTE..1
(4700 50);
FORCEPROP 0 LAST L1 SPOF
J 0
(4561 -99);
DISPLAY 0.617021 (4561 -99);
PAINT WHITE (4561 -99);
FORCEPROP 1 LAST COMMENT_BODY TRUE
J 0
(4725 150);
DISPLAY 0.978723 (4725 150);
PAINT ORANGE (4725 150);
DISPLAY INVISIBLE (4725 150);
FORCEPROP 2 LAST CDS_LIB mstr_symbols
J 0
(4700 50);
PAINT ORANGE (4700 50);
DISPLAY INVISIBLE (4700 50);
FORCEADD DNS..3
(4855 -155);
PAINT RED (4855 -155);
FORCEPROP 2 LAST CDS_LIB mstr_misc
J 0
(4855 -155);
PAINT ORANGE (4855 -155);
DISPLAY INVISIBLE (4855 -155);
FORCEPROP 1 LAST COMMENT_BODY TRUE
R 1
J 0
(4930 -380);
DISPLAY 0.872340 (4930 -380);
PAINT GREEN (4930 -380);
DISPLAY INVISIBLE (4930 -380);
FORCEADD PRELIM..6
(1435 890);
PAINT GRAY (1435 890);
FORCEPROP 1 LAST COMMENT_BODY TRUE
J 0
(1435 890);
PAINT ORANGE (1435 890);
DISPLAY INVISIBLE (1435 890);
FORCEPROP 2 LAST CDS_LIB mstr_misc
J 0
(1435 890);
PAINT ORANGE (1435 890);
DISPLAY INVISIBLE (1435 890);
FORCEADD CAD_NOTE..1
(4700 3475);
FORCEPROP 1 LAST COMMENT_BODY TRUE
J 0
(4725 3575);
DISPLAY 0.978723 (4725 3575);
PAINT ORANGE (4725 3575);
DISPLAY INVISIBLE (4725 3575);
FORCEPROP 2 LAST CDS_LIB mstr_symbols
J 0
(4700 3475);
PAINT ORANGE (4700 3475);
DISPLAY INVISIBLE (4700 3475);
FORCEADD CAD_NOTE..1
(0 2575);
FORCEPROP 0 LAST L1 PLACE CLOSE TO CONTROLLER
J 0
(-87 2483);
DISPLAY 0.617021 (-87 2483);
PAINT WHITE (-87 2483);
FORCEPROP 1 LAST COMMENT_BODY TRUE
J 0
(25 2675);
DISPLAY 0.978723 (25 2675);
PAINT ORANGE (25 2675);
DISPLAY INVISIBLE (25 2675);
FORCEPROP 2 LAST CDS_LIB mstr_symbols
J 0
(0 2575);
PAINT ORANGE (0 2575);
DISPLAY INVISIBLE (0 2575);
FORCEADD DNS..2
(-420 495);
PAINT RED (-420 495);
FORCEPROP 2 LAST CDS_LIB mstr_misc
J 0
(-420 495);
PAINT ORANGE (-420 495);
DISPLAY INVISIBLE (-420 495);
FORCEPROP 1 LAST COMMENT_BODY TRUE
R 1
J 0
(-345 270);
DISPLAY 0.872340 (-345 270);
PAINT GREEN (-345 270);
DISPLAY INVISIBLE (-345 270);
FORCEADD INTEL_CORP_BPAGE..1
(5900 -1250);
FORCEPROP 1 LAST CDS_CON_LAST_MODIFIED Fri Jun 16 17:49:22 2017
J 0
(4475 -925);
PAINT GREEN (4475 -925);
DISPLAY INVISIBLE (4475 -925);
FORCEPROP 1 LAST CUSTOM_TXT_CDS <CURRENT_DESIGN_SHEET> OF <TOTAL_DESIGN_SHEETS>
J 0
(5400 -1225);
PAINT ORANGE (5400 -1225);
FORCEPROP 1 LAST CUSTOM_TXT_CDS <CON_LAST_MODIFIED>
J 0
(1900 -1150);
PAINT ORANGE (1900 -1150);
FORCEPROP 2 LAST CUSTOM_TXT_CDS <XR_PAGE_TITLE>
J 0
(-1990 4000);
DISPLAY 0.638298 (-1990 4000);
PAINT PINK (-1990 4000);
DISPLAY INVISIBLE (-1990 4000);
FORCEPROP 1 LAST SCH_TITLE DDR VTT VR CHANNEL GHJ
J 0
(-2050 -1200);
DISPLAY 1.212766 (-2050 -1200);
PAINT GREEN (-2050 -1200);
FORCEPROP 1 LAST COMMENT_BODY TRUE
J 0
(5912 -1238);
DISPLAY 0.446809 (5912 -1238);
PAINT GREEN (5912 -1238);
DISPLAY INVISIBLE (5912 -1238);
FORCEPROP 2 LAST CDS_LIB mstr_symbols
J 0
(5900 -1250);
PAINT ORANGE (5900 -1250);
DISPLAY INVISIBLE (5900 -1250);
FORCEPROP 2 LAST PAGE_BORDER TRUE
J 0
(-1990 4000);
DISPLAY 0.659574 (-1990 4000);
PAINT PINK (-1990 4000);
DISPLAY INVISIBLE (-1990 4000);
FORCEPROP 2 LAST CDS_XR_PAGE_TITLE CR-229 : @BASEBOARD_FAB2_LIB.BASEBOARD_FAB2(SCH_1):PAGE229
J 0
(-1990 4000);
DISPLAY 0.638298 (-1990 4000);
PAINT PINK (-1990 4000);
DISPLAY INVISIBLE (-1990 4000);
WIRE 16 -1 (-475 -725)(-475 -650);
WIRE 16 -1 (-75 2100)(-75 2000);
WIRE 16 -1 (200 650)(200 725);
WIRE 16 -1 (350 1225)(350 1150);
WIRE 16 -1 (1875 600)(1875 475);
WIRE 16 -1 (1875 700)(1875 600);
WIRE 16 -1 (1725 600)(1875 600);
WIRE 16 -1 (1875 750)(1875 700);
WIRE 16 -1 (1725 700)(1875 700);
WIRE 16 -1 (1725 750)(1875 750);
WIRE 16 -1 (350 2000)(350 2100);
WIRE 16 -1 (2200 475)(2200 575);
WIRE 16 -1 (3850 625)(3850 550);
WIRE 16 -1 (4700 625)(3850 625);
WIRE 16 -1 (3850 800)(3850 625);
WIRE 16 -1 (4700 800)(4700 625);
WIRE 16 -1 (3975 1300)(3975 1350);
WIRE 16 -1 (3325 1950)(3325 2025);
WIRE 16 -1 (3400 3375)(3400 3425);
WIRE 16 -1 (3400 3375)(3800 3375);
WIRE 16 -1 (3400 3375)(3400 3300);
WIRE 16 -1 (4150 3375)(3800 3375);
WIRE 16 -1 (3800 3300)(3800 3375);
WIRE 16 -1 (4150 3300)(4150 3375);
WIRE 16 -1 (5425 1350)(5425 1150);
WIRE 16 -1 (5425 1150)(4700 1150);
WIRE 16 -1 (5425 -150)(5425 1150);
WIRE 16 -1 (5000 -150)(5425 -150);
WIRE 16 -1 (4700 1150)(3850 1150);
WIRE 16 -1 (4700 1000)(4700 1150);
WIRE 16 -1 (1725 1150)(3850 1150);
WIRE 16 -1 (3850 1000)(3850 1150);
WIRE 16 -1 (3400 2925)(3400 2950);
WIRE 16 -1 (3800 2950)(3400 2950);
WIRE 16 -1 (3400 3100)(3400 2950);
WIRE 16 -1 (4150 2950)(3800 2950);
WIRE 16 -1 (3800 3100)(3800 2950);
WIRE 16 -1 (4150 3100)(4150 2950);
WIRE 16 -1 (-600 1850)(-600 1600);
WIRE 16 -1 (-425 1600)(-600 1600);
WIRE 16 -1 (-425 600)(-425 1600);
WIRE 16 -1 (-75 1600)(-425 1600);
WIRE 16 -1 (-1550 2575)(-1550 2375);
WIRE 16 -1 (-1175 2375)(-1550 2375);
WIRE 16 -1 (-1175 2375)(-1175 1400);
WIRE 16 -1 (-1175 2375)(-75 2375);
WIRE 16 -1 (350 2375)(-75 2375);
WIRE 16 -1 (-75 2300)(-75 2375);
WIRE 16 -1 (-950 1400)(-1175 1400);
WIRE 16 -1 (350 2375)(975 2375);
WIRE 16 -1 (350 2300)(350 2375);
WIRE 16 -1 (975 1150)(975 2375);
WIRE 16 -1 (1125 1150)(975 1150);
WIRE 3 682 (3700 3450)(3700 2550);
WIRE 3 682 (4450 3450)(3700 3450);
WIRE 3 682 (3700 2550)(4450 2550);
WIRE 3 682 (4450 2550)(4450 3450);
WIRE 16 2175 (3250 3600)(3250 2450);
WIRE 16 2175 (5675 2450)(3250 2450);
WIRE 16 2175 (5675 3600)(3250 3600);
WIRE 16 2175 (5675 3600)(5675 2450);
WIRE 16 -1 (5025 1650)(4350 1650);
FORCEPROP 2 LAST SIG_NAME PWRGD_PVTT_CPU1
J 0
(4472 1660);
DISPLAY 0.617021 (4472 1660);
PAINT ORANGE (4472 1660);
WIRE 3 682 (5275 550)(4625 550);
WIRE 3 682 (5275 1075)(5275 550);
WIRE 3 682 (4625 550)(4625 1075);
WIRE 3 682 (4625 1075)(5275 1075);
WIRE 16 -1 (1125 900)(525 900);
FORCEPROP 2 LAST SIG_NAME FM_PVTT_GHJ_EN_R
J 0
(-75 -10);
DISPLAY 0.617021 (-75 -10);
PAINT ORANGE (-75 -10);
FORCEPROP 2 LASTPROP $XRERR UNIQUE?
J 0
(-315 -10);
DISPLAY 0.638298 (-315 -10);
PAINT MONO (-315 -10);
DISPLAY INVISIBLE (-315 -10);
WIRE 16 -1 (525 900)(525 -25);
WIRE 16 -1 (-425 -25)(-425 400);
WIRE 16 -1 (525 -25)(-425 -25);
WIRE 16 -1 (-550 -25)(-475 -25);
WIRE 16 -1 (-425 -25)(-475 -25);
WIRE 16 -1 (-475 -450)(-475 -25);
WIRE 16 2175 (-175 1050)(-175 2675);
WIRE 16 2175 (-175 2675)(775 2675);
WIRE 16 2175 (-175 1050)(775 1050);
WIRE 16 2175 (775 1050)(775 2675);
WIRE 16 273 (775 3350)(1925 3350);
WIRE 16 273 (775 3250)(775 3350);
WIRE 16 273 (775 2750)(775 3250);
WIRE 16 273 (1925 2750)(775 2750);
WIRE 16 273 (775 3250)(1925 3250);
WIRE 16 273 (1925 3350)(1925 3250);
WIRE 16 273 (1925 3250)(1925 2750);
WIRE 16 -1 (1725 850)(3325 850);
WIRE 16 -1 (3325 850)(3325 1650);
WIRE 16 -1 (3325 1750)(3325 1650);
WIRE 16 -1 (3975 1650)(3325 1650);
FORCEPROP 2 LAST SIG_NAME PWRGD_PVTT_GHJ_CPU1_R
J 0
(3397 1660);
DISPLAY 0.617021 (3397 1660);
PAINT ORANGE (3397 1660);
FORCEPROP 2 LASTPROP $XRERR UNIQUE?
J 0
(3157 1660);
DISPLAY 0.638298 (3157 1660);
PAINT MONO (3157 1660);
DISPLAY INVISIBLE (3157 1660);
WIRE 16 -1 (4150 1650)(3975 1650);
WIRE 16 -1 (3975 1550)(3975 1650);
WIRE 16 2175 (4425 -25)(5075 -25);
WIRE 16 2175 (5075 -600)(5075 -25);
WIRE 16 2175 (4425 -600)(4425 -25);
WIRE 16 2175 (4425 -600)(5075 -600);
WIRE 16 -1 (1125 800)(850 800);
WIRE 16 -1 (850 800)(850 -150);
WIRE 16 -1 (4700 -150)(850 -150);
FORCEPROP 2 LAST SIG_NAME VR_PVTT_GHJ_SNS
J 0
(902 -145);
DISPLAY 0.617021 (902 -145);
PAINT ORANGE (902 -145);
FORCEPROP 2 LASTPROP $XRERR UNIQUE?
J 0
(662 -145);
DISPLAY 0.638298 (662 -145);
PAINT MONO (662 -145);
DISPLAY INVISIBLE (662 -145);
WIRE 16 -1 (-625 1400)(-750 1400);
WIRE 16 -1 (-625 1000)(-625 1400);
WIRE 16 -1 (200 1000)(-625 1000);
WIRE 16 -1 (200 925)(200 1000);
WIRE 16 -1 (1125 1000)(200 1000);
FORCEPROP 2 LAST SIG_NAME VSENSE_PVDDQ_GHJ_VTT
J 0
(392 1010);
DISPLAY 0.617021 (392 1010);
PAINT ORANGE (392 1010);
FORCEPROP 2 LASTPROP $XRERR UNIQUE?
J 0
(152 1010);
DISPLAY 0.638298 (152 1010);
PAINT MONO (152 1010);
DISPLAY INVISIBLE (152 1010);
WIRE 16 2175 (1925 375)(1925 1500);
WIRE 16 2175 (2725 375)(1925 375);
WIRE 16 2175 (1925 1500)(2725 1500);
WIRE 16 2175 (2725 1500)(2725 375);
WIRE 16 -1 (1125 650)(900 650);
WIRE 16 -1 (900 650)(900 1600);
WIRE 16 -1 (350 1425)(350 1600);
WIRE 16 -1 (900 1600)(350 1600);
WIRE 16 -1 (125 1600)(350 1600);
FORCEPROP 2 LAST SIG_NAME VR_PVTT_GHJ_BIAS
J 0
(195 1620);
DISPLAY 0.617021 (195 1620);
PAINT ORANGE (195 1620);
FORCEPROP 2 LASTPROP $XRERR UNIQUE?
J 0
(-45 1620);
DISPLAY 0.638298 (-45 1620);
PAINT MONO (-45 1620);
DISPLAY INVISIBLE (-45 1620);
WIRE 16 -1 (2200 775)(2200 1050);
WIRE 16 -1 (1725 1050)(2200 1050);
FORCEPROP 2 LAST SIG_NAME VR_PVTT_GHJ_VREF
J 0
(1793 1060);
DISPLAY 0.617021 (1793 1060);
PAINT ORANGE (1793 1060);
FORCEPROP 2 LASTPROP $XRERR UNIQUE?
J 0
(1553 1060);
DISPLAY 0.638298 (1553 1060);
PAINT MONO (1553 1060);
DISPLAY INVISIBLE (1553 1060);
WIRE 16 -1 (-750 -25)(-1475 -25);
FORCEPROP 2 LAST SIG_NAME PWRGD_PVDDQ_GHJ_R
J 0
(-1437 -10);
DISPLAY 0.617021 (-1437 -10);
PAINT ORANGE (-1437 -10);
WIRE 3 682 (-900 -75)(-1950 -75);
WIRE 3 682 (-900 75)(-900 -75);
WIRE 3 682 (-1950 -75)(-1950 75);
WIRE 3 682 (-1950 75)(-900 75);
DOT 1 (3800 3375);
DOT 1 (3400 2950);
DOT 1 (3800 2950);
DOT 1 (4700 1150);
DOT 1 (3400 3375);
DOT 1 (3975 1650);
DOT 1 (3850 1150);
DOT 1 (3325 1650);
DOT 1 (3850 625);
DOT 1 (1925 3250);
DOT 1 (775 3250);
DOT 1 (350 2375);
DOT 1 (1875 700);
DOT 1 (1875 600);
DOT 1 (350 1600);
DOT 1 (200 1000);
DOT 1 (-75 2375);
DOT 1 (-1175 2375);
DOT 1 (-425 1600);
DOT 1 (-425 -25);
DOT 1 (-475 -25);
DOT 1 (5425 1150);
FORCENOTE
TP FAB3 CHANGE CAP 0803
(3675 2475) 0;
DISPLAY LEFT (3675 2475);
DISPLAY 1.021277 (3675 2475);
PAINT RED (3675 2475);
FORCENOTE
IOUT STEP=+1.523A / -1 .546A
(819 2881) 0;
DISPLAY LEFT (819 2881);
DISPLAY 0.808511 (819 2881);
PAINT PURPLE (819 2881);
FORCENOTE
IOUT TDC=+/-1.4A
(819 2931) 0;
DISPLAY LEFT (819 2931);
DISPLAY 0.808511 (819 2931);
PAINT PURPLE (819 2931);
FORCENOTE
IOUT PEAK=+-/1.4A
(819 2981) 0;
DISPLAY LEFT (819 2981);
DISPLAY 0.808511 (819 2981);
PAINT PURPLE (819 2981);
FORCENOTE
RIPPLE GUIDELINE= +/-1%
(819 3131) 0;
DISPLAY LEFT (819 3131);
DISPLAY 0.808511 (819 3131);
PAINT PURPLE (819 3131);
FORCENOTE
IOUT DI/DT=6A/US
(819 2831) 0;
DISPLAY LEFT (819 2831);
DISPLAY 0.808511 (819 2831);
PAINT PURPLE (819 2831);
FORCENOTE
PVTT DDR SPECIFICATION:
(819 3281) 0;
DISPLAY LEFT (819 3281);
PAINT PURPLE (819 3281);
FORCENOTE
VOUT=0.5 VDDQ
(819 3181) 0;
DISPLAY LEFT (819 3181);
DISPLAY 0.808511 (819 3181);
PAINT PURPLE (819 3181);
FORCENOTE
DC TOL= +/-1.5%
(819 3081) 0;
DISPLAY LEFT (819 3081);
DISPLAY 0.808511 (819 3081);
PAINT PURPLE (819 3081);
FORCENOTE
AC & RIPPLE=+3.5/-7.3%
(819 3031) 0;
DISPLAY LEFT (819 3031);
DISPLAY 0.808511 (819 3031);
PAINT PURPLE (819 3031);
FORCENOTE
CRTICAL: PLACE 0 OHM NEAR  VDDQ SENSE RESISTOR.
(-1789 1219) 0;
DISPLAY LEFT (-1789 1219);
DISPLAY 1.021277 (-1789 1219);
PAINT PURPLE (-1789 1219);
FORCENOTE
TP FAB1 CHANGE CONNECTION 0303
(-1850 125) 0;
DISPLAY LEFT (-1850 125);
DISPLAY 1.021277 (-1850 125);
PAINT RED (-1850 125);
FORCENOTE
PLACED BETWEEN DIMMS
(4550 3345) 0;
DISPLAY LEFT (4550 3345);
DISPLAY 1.021277 (4550 3345);
PAINT PURPLE (4550 3345);
FORCENOTE
TP FAB1 CHANGE RES TO CAP 0311
(4550 500) 0;
DISPLAY LEFT (4550 500);
DISPLAY 1.021277 (4550 500);
PAINT RED (4550 500);
FORCENOTE
ROOM = VTT_GHJ_PWR_VR
(-1756 3458) 0;
DISPLAY LEFT (-1756 3458);
DISPLAY 1.595745 (-1756 3458);
PAINT PURPLE (-1756 3458);
QUIT
